# Altium SchDoc records: 08-DIPSwitches_I2C.SchDoc
|HEADER=Protel for Windows - Schematic Capture Binary File Version 5.0|Weight=1857|MinorVersion=7
|RECORD=31|FontIdCount=3|Size1=10|FontName1=Times New Roman|Size2=10|Rotation2=90|FontName2=Times New Roman|Size3=10|Underline3=T|FontName3=Times New Roman|UseMBCS=T|IsBOC=T|HotSpotGridOn=T|HotSpotGridSize=4|SheetStyle=6|SystemFont=1|BorderOn=T|TitleBlockOn=T|SheetNumberSpaceSize=12|AreaColor=16317695|SnapGridOn=T|SnapGridSize=10|VisibleGridOn=T|VisibleGridSize=10|CustomX=1500|CustomY=950|CustomXZones=6|CustomYZones=4|CustomMarginWidth=20|Display_Unit=0
|RECORD=41|OwnerPartId=-1|Color=8388608|FontID=1|IsHidden=T|Text=*|Name=CurrentTime|ReadOnlyState=1
|RECORD=41|IndexInSheet=1|OwnerPartId=-1|Color=8388608|FontID=1|IsHidden=T|Text=*|Name=CurrentDate|ReadOnlyState=1
|RECORD=41|IndexInSheet=2|OwnerPartId=-1|Color=8388608|FontID=1|IsHidden=T|Text=*|Name=Time|ReadOnlyState=1
|RECORD=41|IndexInSheet=3|OwnerPartId=-1|Color=8388608|FontID=1|IsHidden=T|Text=*|Name=Date|ReadOnlyState=1
|RECORD=41|IndexInSheet=4|OwnerPartId=-1|Color=8388608|FontID=1|IsHidden=T|Text=*|Name=DocumentFullPathAndName|ReadOnlyState=1
|RECORD=41|IndexInSheet=5|OwnerPartId=-1|Color=8388608|FontID=1|IsHidden=T|Text=*|Name=DocumentName|ReadOnlyState=1
|RECORD=41|IndexInSheet=6|OwnerPartId=-1|Color=8388608|FontID=1|IsHidden=T|Text=*|Name=ModifiedDate|ReadOnlyState=1
|RECORD=41|IndexInSheet=7|OwnerPartId=-1|Color=8388608|FontID=1|IsHidden=T|Text=*|Name=ApprovedBy|ReadOnlyState=1
|RECORD=41|IndexInSheet=8|OwnerPartId=-1|Color=8388608|FontID=1|IsHidden=T|Text=*|Name=CheckedBy|ReadOnlyState=1
|RECORD=41|IndexInSheet=9|OwnerPartId=-1|Color=8388608|FontID=1|IsHidden=T|Text=*|Name=Author|ReadOnlyState=1
|RECORD=41|IndexInSheet=10|OwnerPartId=-1|Color=8388608|FontID=1|IsHidden=T|Text=*|Name=CompanyName|ReadOnlyState=1
|RECORD=41|IndexInSheet=11|OwnerPartId=-1|Color=8388608|FontID=1|IsHidden=T|Text=*|Name=DrawnBy|ReadOnlyState=1
|RECORD=41|IndexInSheet=12|OwnerPartId=-1|Color=8388608|FontID=1|IsHidden=T|Text=*|Name=Engineer|ReadOnlyState=1
|RECORD=41|IndexInSheet=13|OwnerPartId=-1|Color=8388608|FontID=1|IsHidden=T|Text=*|Name=Organization|ReadOnlyState=1
|RECORD=41|IndexInSheet=14|OwnerPartId=-1|Color=8388608|FontID=1|IsHidden=T|Text=*|Name=Address1|ReadOnlyState=1
|RECORD=41|IndexInSheet=15|OwnerPartId=-1|Color=8388608|FontID=1|IsHidden=T|Text=*|Name=Address2|ReadOnlyState=1
|RECORD=41|IndexInSheet=16|OwnerPartId=-1|Color=8388608|FontID=1|IsHidden=T|Text=*|Name=Address3|ReadOnlyState=1
|RECORD=41|IndexInSheet=17|OwnerPartId=-1|Color=8388608|FontID=1|IsHidden=T|Text=*|Name=Address4|ReadOnlyState=1
|RECORD=41|IndexInSheet=18|OwnerPartId=-1|Color=8388608|FontID=1|IsHidden=T|Text=*|Name=Title|ReadOnlyState=1
|RECORD=41|IndexInSheet=19|OwnerPartId=-1|Color=8388608|FontID=1|IsHidden=T|Text=*|Name=DocumentNumber|ReadOnlyState=1
|RECORD=41|IndexInSheet=20|OwnerPartId=-1|Color=8388608|FontID=1|IsHidden=T|Text=*|Name=Revision|ReadOnlyState=1
|RECORD=41|IndexInSheet=21|OwnerPartId=-1|Color=8388608|FontID=1|IsHidden=T|Text=*|Name=SheetNumber|ReadOnlyState=1
|RECORD=41|IndexInSheet=22|OwnerPartId=-1|Color=8388608|FontID=1|IsHidden=T|Text=*|Name=SheetTotal|ReadOnlyState=1
|RECORD=41|IndexInSheet=23|OwnerPartId=-1|Color=8388608|FontID=1|IsHidden=T|Text=*|Name=Rule|ReadOnlyState=1
|RECORD=41|IndexInSheet=24|OwnerPartId=-1|Color=8388608|FontID=1|IsHidden=T|Text=*|Name=ImagePath|ReadOnlyState=1
|RECORD=41|IndexInSheet=25|OwnerPartId=-1|Color=8388608|FontID=1|IsHidden=T|Text=*|Name=ProjectName|ReadOnlyState=1
|RECORD=41|IndexInSheet=26|OwnerPartId=-1|Color=8388608|FontID=1|IsHidden=T|Text=*|Name=Application_BuildNumber|ReadOnlyState=1
|RECORD=4|IndexInSheet=27|OwnerPartId=-1|Location.X=130|Location.Y=870|Color=8388608|FontID=1|Text=DIP Switch, Configure UART and PPS Single ended versus differential
|RECORD=17|IndexInSheet=28|OwnerPartId=-1|Style=4|ShowNetName=T|Location.X=180|Location.Y=530|Orientation=3|Color=128|FontID=1|Text=GND
|RECORD=17|IndexInSheet=29|OwnerPartId=-1|Style=1|ShowNetName=T|Location.X=420|Location.Y=730|Color=255|FontID=1|Text=DIP_SW_UART_SEL|IsCrossSheetConnector=T
|RECORD=17|IndexInSheet=30|OwnerPartId=-1|Style=1|ShowNetName=T|Location.X=420|Location.Y=690|Color=255|FontID=1|Text=DIP_SW_PPS_SEL|IsCrossSheetConnector=T
|RECORD=4|IndexInSheet=31|OwnerPartId=-1|Location.X=190|Location.Y=860|Color=8388608|FontID=1|Text=UART either goes to FPGA or to GPS2
|RECORD=1|LibReference=RES|PartCount=2|DisplayModeCount=2|IndexInSheet=32|OwnerPartId=-1|Location.X=310|Location.Y=770|Orientation=3|CurrentPartId=1|SourceLibraryName=Altium Content Vault|TargetFileName=*|AreaColor=11599871|Color=128|PartIDLocked=F|DesignItemId=CMP-2002-07353-1|AllPinCount=2
|RECORD=2|OwnerIndex=33|OwnerPartId=1|OwnerPartDisplayMode=1|FormalType=1|Electrical=4|PinConglomerate=35|PinLength=10|Location.X=300|Location.Y=750|Name=2|Designator=2|PinPropagationDelay=0.000000E+000
|RECORD=2|OwnerIndex=33|OwnerPartId=1|OwnerPartDisplayMode=1|FormalType=1|Electrical=4|PinConglomerate=33|PinLength=10|Location.X=300|Location.Y=770|Name=1|Designator=1|PinPropagationDelay=0.000000E+000
|RECORD=14|OwnerIndex=33|IsNotAccesible=T|IndexInSheet=2|OwnerPartId=1|OwnerPartDisplayMode=1|Location.X=296|Location.Y=750|Corner.X=304|Corner.Y=770|LineWidth=1|Color=16711680|AreaColor=11599871
|RECORD=2|OwnerIndex=33|OwnerPartId=1|FormalType=1|Electrical=4|PinConglomerate=35|PinLength=10|Location.X=300|Location.Y=750|Name=2|Designator=2|PinPropagationDelay=0.000000E+000
|RECORD=2|OwnerIndex=33|OwnerPartId=1|FormalType=1|Electrical=4|PinConglomerate=33|PinLength=10|Location.X=300|Location.Y=770|Name=1|Designator=1|PinPropagationDelay=0.000000E+000
|RECORD=6|OwnerIndex=33|IsNotAccesible=T|IndexInSheet=5|OwnerPartId=1|LineWidth=1|Color=16711680|LocationCount=10|X1=300|Y1=750|X2=300|Y2=754|X3=298|Y3=755|X4=302|Y4=757|X5=298|Y5=759|X6=302|Y6=761|X7=298|Y7=763|X8=302|Y8=765|X9=300|Y9=766|X10=300|Y10=770
|RECORD=41|OwnerIndex=33|IndexInSheet=6|OwnerPartId=-1|Location.X=297|Location.Y=782|Color=8388608|FontID=1|IsHidden=T|Text=RC0402FR-0710KL|Name=Part Number
|RECORD=41|OwnerIndex=33|IndexInSheet=7|OwnerPartId=-1|Location.X=297|Location.Y=782|Color=8388608|FontID=1|IsHidden=T|Text=Yageo / Phycomp|Name=Manufacturer
|RECORD=34|OwnerIndex=33|IndexInSheet=-1|OwnerPartId=-1|Location.X=300|Location.Y=740|Orientation=1|Color=8388608|FontID=2|Text=R78|Name=Designator|ReadOnlyState=1
|RECORD=41|OwnerIndex=33|IndexInSheet=-1|OwnerPartId=-1|Location.X=310|Location.Y=740|Orientation=1|Color=8388608|FontID=2|Text=10K_1%_0402|Name=Comment
|RECORD=44|OwnerIndex=33
|RECORD=45|OwnerIndex=48|IndexInSheet=-1|Description=Chip Resistor, 2-Leads, Body 1.00x0.50mm, IPC High Density|UseComponentLibrary=T|ModelName=RESC1005X40X25LL05T10|ModelType=PCBLIB|DatafileCount=1|ModelDatafileEntity0=RESC1005X40X25LL05T10|ModelDatafileKind0=PCBLib|IsCurrent=T|DatalinksLocked=T|DatabaseDatalinksLocked=T
|RECORD=46|OwnerIndex=49
|RECORD=48|OwnerIndex=49
|RECORD=41|OwnerIndex=51|IndexInSheet=-1|OwnerPartId=-1|Color=8388608|FontID=1|IsHidden=T|Text=2D|Name=Available Preview Images
|RECORD=45|OwnerIndex=48|IndexInSheet=-1|Description=Chip Resistor, 2-Leads, Body 1.00x0.50mm, IPC Low Density|UseComponentLibrary=T|ModelName=RESC1005X40X25ML05T10|ModelType=PCBLIB|DatafileCount=1|ModelDatafileEntity0=RESC1005X40X25ML05T10|ModelDatafileKind0=PCBLib|DatalinksLocked=T|DatabaseDatalinksLocked=T
|RECORD=46|OwnerIndex=53
|RECORD=48|OwnerIndex=53
|RECORD=41|OwnerIndex=55|IndexInSheet=-1|OwnerPartId=-1|Color=8388608|FontID=1|IsHidden=T|Text=2D|Name=Available Preview Images
|RECORD=45|OwnerIndex=48|IndexInSheet=-1|Description=Chip Resistor, 2-Leads, Body 1.00x0.50mm, IPC Medium Density|UseComponentLibrary=T|ModelName=RESC1005X40X25NL05T10|ModelType=PCBLIB|DatafileCount=1|ModelDatafileEntity0=RESC1005X40X25NL05T10|ModelDatafileKind0=PCBLib|DatalinksLocked=T|DatabaseDatalinksLocked=T
|RECORD=46|OwnerIndex=57
|RECORD=48|OwnerIndex=57
|RECORD=41|OwnerIndex=59|IndexInSheet=-1|OwnerPartId=-1|Color=8388608|FontID=1|IsHidden=T|Text=2D|Name=Available Preview Images
|RECORD=17|IndexInSheet=33|OwnerPartId=-1|ShowNetName=T|Location.X=300|Location.Y=800|Orientation=1|Color=128|FontID=1|Text=+3.3V
|RECORD=1|LibReference=RES|PartCount=2|DisplayModeCount=2|IndexInSheet=34|OwnerPartId=-1|Location.X=330|Location.Y=770|Orientation=3|CurrentPartId=1|SourceLibraryName=Altium Content Vault|TargetFileName=*|AreaColor=11599871|Color=128|PartIDLocked=F|DesignItemId=CMP-2002-07353-1|AllPinCount=2
|RECORD=2|OwnerIndex=62|OwnerPartId=1|OwnerPartDisplayMode=1|FormalType=1|Electrical=4|PinConglomerate=35|PinLength=10|Location.X=320|Location.Y=750|Name=2|Designator=2|PinPropagationDelay=0.000000E+000
|RECORD=2|OwnerIndex=62|OwnerPartId=1|OwnerPartDisplayMode=1|FormalType=1|Electrical=4|PinConglomerate=33|PinLength=10|Location.X=320|Location.Y=770|Name=1|Designator=1|PinPropagationDelay=0.000000E+000
|RECORD=14|OwnerIndex=62|IsNotAccesible=T|IndexInSheet=2|OwnerPartId=1|OwnerPartDisplayMode=1|Location.X=316|Location.Y=750|Corner.X=324|Corner.Y=770|LineWidth=1|Color=16711680|AreaColor=11599871
|RECORD=2|OwnerIndex=62|OwnerPartId=1|FormalType=1|Electrical=4|PinConglomerate=35|PinLength=10|Location.X=320|Location.Y=750|Name=2|Designator=2|PinPropagationDelay=0.000000E+000
|RECORD=2|OwnerIndex=62|OwnerPartId=1|FormalType=1|Electrical=4|PinConglomerate=33|PinLength=10|Location.X=320|Location.Y=770|Name=1|Designator=1|PinPropagationDelay=0.000000E+000
|RECORD=6|OwnerIndex=62|IsNotAccesible=T|IndexInSheet=5|OwnerPartId=1|LineWidth=1|Color=16711680|LocationCount=10|X1=320|Y1=750|X2=320|Y2=754|X3=318|Y3=755|X4=322|Y4=757|X5=318|Y5=759|X6=322|Y6=761|X7=318|Y7=763|X8=322|Y8=765|X9=320|Y9=766|X10=320|Y10=770
|RECORD=41|OwnerIndex=62|IndexInSheet=6|OwnerPartId=-1|Location.X=317|Location.Y=782|Color=8388608|FontID=1|IsHidden=T|Text=RC0402FR-0710KL|Name=Part Number
|RECORD=41|OwnerIndex=62|IndexInSheet=7|OwnerPartId=-1|Location.X=317|Location.Y=782|Color=8388608|FontID=1|IsHidden=T|Text=Yageo / Phycomp|Name=Manufacturer
|RECORD=34|OwnerIndex=62|IndexInSheet=-1|OwnerPartId=-1|Location.X=320|Location.Y=740|Orientation=1|Color=8388608|FontID=2|Text=R88|Name=Designator|ReadOnlyState=1
|RECORD=41|OwnerIndex=62|IndexInSheet=-1|OwnerPartId=-1|Location.X=330|Location.Y=740|Orientation=1|Color=8388608|FontID=2|Text=10K_1%_0402|Name=Comment
|RECORD=44|OwnerIndex=62
|RECORD=45|OwnerIndex=77|IndexInSheet=-1|Description=Chip Resistor, 2-Leads, Body 1.00x0.50mm, IPC High Density|UseComponentLibrary=T|ModelName=RESC1005X40X25LL05T10|ModelType=PCBLIB|DatafileCount=1|ModelDatafileEntity0=RESC1005X40X25LL05T10|ModelDatafileKind0=PCBLib|IsCurrent=T|DatalinksLocked=T|DatabaseDatalinksLocked=T
|RECORD=46|OwnerIndex=78
|RECORD=48|OwnerIndex=78
|RECORD=41|OwnerIndex=80|IndexInSheet=-1|OwnerPartId=-1|Color=8388608|FontID=1|IsHidden=T|Text=2D|Name=Available Preview Images
|RECORD=45|OwnerIndex=77|IndexInSheet=-1|Description=Chip Resistor, 2-Leads, Body 1.00x0.50mm, IPC Low Density|UseComponentLibrary=T|ModelName=RESC1005X40X25ML05T10|ModelType=PCBLIB|DatafileCount=1|ModelDatafileEntity0=RESC1005X40X25ML05T10|ModelDatafileKind0=PCBLib|DatalinksLocked=T|DatabaseDatalinksLocked=T
|RECORD=46|OwnerIndex=82
|RECORD=48|OwnerIndex=82
|RECORD=41|OwnerIndex=84|IndexInSheet=-1|OwnerPartId=-1|Color=8388608|FontID=1|IsHidden=T|Text=2D|Name=Available Preview Images
|RECORD=45|OwnerIndex=77|IndexInSheet=-1|Description=Chip Resistor, 2-Leads, Body 1.00x0.50mm, IPC Medium Density|UseComponentLibrary=T|ModelName=RESC1005X40X25NL05T10|ModelType=PCBLIB|DatafileCount=1|ModelDatafileEntity0=RESC1005X40X25NL05T10|ModelDatafileKind0=PCBLib|DatalinksLocked=T|DatabaseDatalinksLocked=T
|RECORD=46|OwnerIndex=86
|RECORD=48|OwnerIndex=86
|RECORD=41|OwnerIndex=88|IndexInSheet=-1|OwnerPartId=-1|Color=8388608|FontID=1|IsHidden=T|Text=2D|Name=Available Preview Images
|RECORD=4|IndexInSheet=35|OwnerPartId=-1|Location.X=120|Location.Y=840|Color=8388608|FontID=1|Text=UART_SEL = 0 for FTDI <-> GPS2, 1 for FTDI <-> FPGA and FPGA <-> GPS2
|RECORD=4|IndexInSheet=36|OwnerPartId=-1|Location.X=150|Location.Y=830|Color=8388608|FontID=1|Text=PPS_SEL = 0 for Single Ended PPS, 1 for Differential PPS (SA53)
|RECORD=1|LibReference=RES|PartCount=2|DisplayModeCount=2|IndexInSheet=37|OwnerPartId=-1|Location.X=350|Location.Y=770|Orientation=3|CurrentPartId=1|SourceLibraryName=Altium Content Vault|TargetFileName=*|AreaColor=11599871|Color=128|PartIDLocked=F|DesignItemId=CMP-2002-07353-1|AllPinCount=2
|RECORD=2|OwnerIndex=92|OwnerPartId=1|OwnerPartDisplayMode=1|FormalType=1|Electrical=4|PinConglomerate=35|PinLength=10|Location.X=340|Location.Y=750|Name=2|Designator=2|PinPropagationDelay=0.000000E+000
|RECORD=2|OwnerIndex=92|OwnerPartId=1|OwnerPartDisplayMode=1|FormalType=1|Electrical=4|PinConglomerate=33|PinLength=10|Location.X=340|Location.Y=770|Name=1|Designator=1|PinPropagationDelay=0.000000E+000
|RECORD=14|OwnerIndex=92|IsNotAccesible=T|IndexInSheet=2|OwnerPartId=1|OwnerPartDisplayMode=1|Location.X=336|Location.Y=750|Corner.X=344|Corner.Y=770|LineWidth=1|Color=16711680|AreaColor=11599871
|RECORD=2|OwnerIndex=92|OwnerPartId=1|FormalType=1|Electrical=4|PinConglomerate=35|PinLength=10|Location.X=340|Location.Y=750|Name=2|Designator=2|PinPropagationDelay=0.000000E+000
|RECORD=2|OwnerIndex=92|OwnerPartId=1|FormalType=1|Electrical=4|PinConglomerate=33|PinLength=10|Location.X=340|Location.Y=770|Name=1|Designator=1|PinPropagationDelay=0.000000E+000
|RECORD=6|OwnerIndex=92|IsNotAccesible=T|IndexInSheet=5|OwnerPartId=1|LineWidth=1|Color=16711680|LocationCount=10|X1=340|Y1=750|X2=340|Y2=754|X3=338|Y3=755|X4=342|Y4=757|X5=338|Y5=759|X6=342|Y6=761|X7=338|Y7=763|X8=342|Y8=765|X9=340|Y9=766|X10=340|Y10=770
|RECORD=41|OwnerIndex=92|IndexInSheet=6|OwnerPartId=-1|Location.X=337|Location.Y=782|Color=8388608|FontID=1|IsHidden=T|Text=RC0402FR-0710KL|Name=Part Number
|RECORD=41|OwnerIndex=92|IndexInSheet=7|OwnerPartId=-1|Location.X=337|Location.Y=782|Color=8388608|FontID=1|IsHidden=T|Text=Yageo / Phycomp|Name=Manufacturer
|RECORD=34|OwnerIndex=92|IndexInSheet=-1|OwnerPartId=-1|Location.X=340|Location.Y=740|Orientation=1|Color=8388608|FontID=2|Text=R89|Name=Designator|ReadOnlyState=1
|RECORD=41|OwnerIndex=92|IndexInSheet=-1|OwnerPartId=-1|Location.X=350|Location.Y=740|Orientation=1|Color=8388608|FontID=2|Text=10K_1%_0402|Name=Comment
|RECORD=44|OwnerIndex=92
|RECORD=45|OwnerIndex=107|IndexInSheet=-1|Description=Chip Resistor, 2-Leads, Body 1.00x0.50mm, IPC High Density|UseComponentLibrary=T|ModelName=RESC1005X40X25LL05T10|ModelType=PCBLIB|DatafileCount=1|ModelDatafileEntity0=RESC1005X40X25LL05T10|ModelDatafileKind0=PCBLib|IsCurrent=T|DatalinksLocked=T|DatabaseDatalinksLocked=T
|RECORD=46|OwnerIndex=108
|RECORD=48|OwnerIndex=108
|RECORD=41|OwnerIndex=110|IndexInSheet=-1|OwnerPartId=-1|Color=8388608|FontID=1|IsHidden=T|Text=2D|Name=Available Preview Images
|RECORD=45|OwnerIndex=107|IndexInSheet=-1|Description=Chip Resistor, 2-Leads, Body 1.00x0.50mm, IPC Low Density|UseComponentLibrary=T|ModelName=RESC1005X40X25ML05T10|ModelType=PCBLIB|DatafileCount=1|ModelDatafileEntity0=RESC1005X40X25ML05T10|ModelDatafileKind0=PCBLib|DatalinksLocked=T|DatabaseDatalinksLocked=T
|RECORD=46|OwnerIndex=112
|RECORD=48|OwnerIndex=112
|RECORD=41|OwnerIndex=114|IndexInSheet=-1|OwnerPartId=-1|Color=8388608|FontID=1|IsHidden=T|Text=2D|Name=Available Preview Images
|RECORD=45|OwnerIndex=107|IndexInSheet=-1|Description=Chip Resistor, 2-Leads, Body 1.00x0.50mm, IPC Medium Density|UseComponentLibrary=T|ModelName=RESC1005X40X25NL05T10|ModelType=PCBLIB|DatafileCount=1|ModelDatafileEntity0=RESC1005X40X25NL05T10|ModelDatafileKind0=PCBLib|DatalinksLocked=T|DatabaseDatalinksLocked=T
|RECORD=46|OwnerIndex=116
|RECORD=48|OwnerIndex=116
|RECORD=41|OwnerIndex=118|IndexInSheet=-1|OwnerPartId=-1|Color=8388608|FontID=1|IsHidden=T|Text=2D|Name=Available Preview Images
|RECORD=17|IndexInSheet=38|OwnerPartId=-1|Style=1|ShowNetName=T|Location.X=420|Location.Y=650|Color=255|FontID=1|Text=DIP_SW_MACSER_SEL|IsCrossSheetConnector=T
|RECORD=17|IndexInSheet=39|OwnerPartId=-1|Style=1|ShowNetName=T|Location.X=170|Location.Y=310|Orientation=2|Color=255|FontID=1|Text=DIP_SW_PPS_SEL|IsCrossSheetConnector=T
|RECORD=4|IndexInSheet=40|OwnerPartId=-1|Location.X=190|Location.Y=430|Color=8388608|FontID=1|Text=Status LEDs
|RECORD=4|IndexInSheet=41|OwnerPartId=-1|Location.X=140|Location.Y=360|Color=8388608|FontID=1|Text=PPS_SEL = 0 for Single Ended PPS, 1 for Differential PPS (SA53)
|RECORD=4|IndexInSheet=42|OwnerPartId=-1|Location.X=140|Location.Y=460|Color=8388608|FontID=1|Text=UART_SEL = 0 for FTDI <-> GPS2, 1 for FTDI <-> FPGA and FPGA <-> GPS2
|RECORD=1|LibReference=8706943c75ba83719d021d2fdc84c58|ComponentDescription=LED GREEN CLEAR SMD|PartCount=2|DisplayModeCount=1|IndexInSheet=43|OwnerPartId=-1|Location.X=290|Location.Y=310|Orientation=2|CurrentPartId=1|LibraryPath=*|SourceLibraryName=Altium Content Vault|TargetFileName=*|AreaColor=11599871|Color=128|PartIDLocked=T|DesignItemId=CMP-2000-05198-2|AllPinCount=2
|RECORD=2|OwnerIndex=125|OwnerPartId=1|Electrical=4|PinConglomerate=48|PinLength=20|Location.X=270|Location.Y=310|Name=A|Designator=2|PinPropagationDelay=0.000000E+000
|RECORD=2|OwnerIndex=125|OwnerPartId=1|Electrical=4|PinConglomerate=50|PinLength=20|Location.X=250|Location.Y=310|Name=C|Designator=1|PinPropagationDelay=0.000000E+000
|RECORD=13|OwnerIndex=125|IsNotAccesible=T|IndexInSheet=2|OwnerPartId=1|Location.X=270|Location.Y=300|Corner.X=270|Corner.Y=320|LineWidth=1|Color=16711680
|RECORD=13|OwnerIndex=125|IsNotAccesible=T|IndexInSheet=3|OwnerPartId=1|Location.X=250|Location.Y=300|Corner.X=250|Corner.Y=320|LineWidth=1|Color=16711680
|RECORD=13|OwnerIndex=125|IsNotAccesible=T|IndexInSheet=4|OwnerPartId=1|Location.X=270|Location.Y=300|Corner.X=250|Corner.Y=310|LineWidth=1|Color=16711680
|RECORD=13|OwnerIndex=125|IsNotAccesible=T|IndexInSheet=5|OwnerPartId=1|Location.X=270|Location.Y=320|Corner.X=250|Corner.Y=310|LineWidth=1|Color=16711680
|RECORD=13|OwnerIndex=125|IsNotAccesible=T|IndexInSheet=6|OwnerPartId=1|Location.X=265|Location.Y=298|Corner.X=255|Corner.Y=288|LineWidth=1|Color=16711680
|RECORD=13|OwnerIndex=125|IsNotAccesible=T|IndexInSheet=7|OwnerPartId=1|Location.X=255|Location.Y=288|Corner.X=260|Corner.Y=288|LineWidth=1|Color=16711680
|RECORD=13|OwnerIndex=125|IsNotAccesible=T|IndexInSheet=8|OwnerPartId=1|Location.X=255|Location.Y=288|Corner.X=255|Corner.Y=293|LineWidth=1|Color=16711680
|RECORD=13|OwnerIndex=125|IsNotAccesible=T|IndexInSheet=9|OwnerPartId=1|Location.X=258|Location.Y=302|Corner.X=248|Corner.Y=292|LineWidth=1|Color=16711680
|RECORD=13|OwnerIndex=125|IsNotAccesible=T|IndexInSheet=10|OwnerPartId=1|Location.X=248|Location.Y=292|Corner.X=253|Corner.Y=292|LineWidth=1|Color=16711680
|RECORD=13|OwnerIndex=125|IsNotAccesible=T|IndexInSheet=11|OwnerPartId=1|Location.X=248|Location.Y=292|Corner.X=248|Corner.Y=297|LineWidth=1|Color=16711680
|RECORD=13|OwnerIndex=125|IsNotAccesible=T|IndexInSheet=12|OwnerPartId=1|Location.X=270|Location.Y=310|Corner.X=273|Corner.Y=310|LineWidth=1|Color=16711680
|RECORD=13|OwnerIndex=125|IsNotAccesible=T|IndexInSheet=13|OwnerPartId=1|Location.X=250|Location.Y=310|Corner.X=247|Corner.Y=310|LineWidth=1|Color=16711680
|RECORD=41|OwnerIndex=125|IndexInSheet=14|OwnerPartId=-1|Location.X=228|Location.Y=321|Color=8388608|FontID=1|IsHidden=T|Text=0.8mm|Name=Width
|RECORD=41|OwnerIndex=125|IndexInSheet=15|OwnerPartId=-1|Location.X=228|Location.Y=321|Color=8388608|FontID=1|IsHidden=T|Text=0603|Name=Case Code (Imperial)
|RECORD=41|OwnerIndex=125|IndexInSheet=16|OwnerPartId=-1|Location.X=228|Location.Y=321|Color=8388608|FontID=1|IsHidden=T|Text=2|Name=Number of Pins
|RECORD=41|OwnerIndex=125|IndexInSheet=17|OwnerPartId=-1|Location.X=228|Location.Y=321|Color=8388608|FontID=1|IsHidden=T|Text=75mW|Name=Max Power Dissipation
|RECORD=41|OwnerIndex=125|IndexInSheet=18|OwnerPartId=-1|Location.X=228|Location.Y=321|Color=8388608|FontID=1|IsHidden=T|Text=30mA|Name=Forward Current
|RECORD=41|OwnerIndex=125|IndexInSheet=19|OwnerPartId=-1|Location.X=228|Location.Y=321|Color=8388608|FontID=1|IsHidden=T|Text=Lead Free|Name=Lead Free
|RECORD=41|OwnerIndex=125|IndexInSheet=20|OwnerPartId=-1|Location.X=228|Location.Y=321|Color=8388608|FontID=1|IsHidden=T|Text=5V|Name=Reverse Voltage
|RECORD=41|OwnerIndex=125|IndexInSheet=21|OwnerPartId=-1|Location.X=228|Location.Y=321|Color=8388608|FontID=1|IsHidden=T|Text=Colorless|Name=Lens Color
|RECORD=41|OwnerIndex=125|IndexInSheet=22|OwnerPartId=-1|Location.X=228|Location.Y=321|Color=8388608|FontID=1|IsHidden=T|Text=2V|Name=Forward Voltage
|RECORD=41|OwnerIndex=125|IndexInSheet=23|OwnerPartId=-1|Location.X=228|Location.Y=321|Color=8388608|FontID=1|IsHidden=T|Text=Tape and Reel|Name=Packaging
|RECORD=41|OwnerIndex=125|IndexInSheet=24|OwnerPartId=-1|Location.X=228|Location.Y=321|Color=8388608|FontID=1|IsHidden=T|Text=1|Name=Package Quantity
|RECORD=41|OwnerIndex=125|IndexInSheet=25|OwnerPartId=-1|Location.X=228|Location.Y=321|Color=8388608|FontID=1|IsHidden=T|Text=-55°C|Name=Min Operating Temperature
|RECORD=41|OwnerIndex=125|IndexInSheet=26|OwnerPartId=-1|Location.X=228|Location.Y=321|Color=8388608|FontID=1|IsHidden=T|Text=0603|Name=Case/Package
|RECORD=41|OwnerIndex=125|IndexInSheet=27|OwnerPartId=-1|Location.X=228|Location.Y=321|Color=8388608|FontID=1|IsHidden=T|Text=1.6mm|Name=Length
|RECORD=41|OwnerIndex=125|IndexInSheet=28|OwnerPartId=-1|Location.X=228|Location.Y=321|Color=8388608|FontID=1|IsHidden=T|Text=75mW|Name=Power Dissipation
|RECORD=41|OwnerIndex=125|IndexInSheet=29|OwnerPartId=-1|Location.X=228|Location.Y=321|Color=8388608|FontID=1|IsHidden=T|Text=571nm|Name=Dominant Wavelength
|RECORD=41|OwnerIndex=125|IndexInSheet=30|OwnerPartId=-1|Location.X=228|Location.Y=321|Color=8388608|FontID=1|IsHidden=T|Text=0.8mm|Name=Depth
|RECORD=41|OwnerIndex=125|IndexInSheet=31|OwnerPartId=-1|Location.X=228|Location.Y=321|Color=8388608|FontID=1|IsHidden=T|Text=No|Name=Radiation Hardening
|RECORD=41|OwnerIndex=125|IndexInSheet=32|OwnerPartId=-1|Location.X=228|Location.Y=321|Color=8388608|FontID=1|IsHidden=T|Text=Surface Mount|Name=Mount
|RECORD=41|OwnerIndex=125|IndexInSheet=33|OwnerPartId=-1|Location.X=228|Location.Y=321|Color=8388608|FontID=1|IsHidden=T|Text=85°C|Name=Max Operating Temperature
|RECORD=41|OwnerIndex=125|IndexInSheet=34|OwnerPartId=-1|Location.X=228|Location.Y=321|Color=8388608|FontID=1|IsHidden=T|Text=Green|Name=Color
|RECORD=41|OwnerIndex=125|IndexInSheet=35|OwnerPartId=-1|Location.X=228|Location.Y=321|Color=8388608|FontID=1|IsHidden=T|Text=75mW|Name=Power Rating
|RECORD=41|OwnerIndex=125|IndexInSheet=36|OwnerPartId=-1|Location.X=228|Location.Y=321|Color=8388608|FontID=1|IsHidden=T|Text=0.55mm|Name=Height
|RECORD=41|OwnerIndex=125|IndexInSheet=37|OwnerPartId=-1|Location.X=228|Location.Y=321|Color=8388608|FontID=1|IsHidden=T|Text=1|Name=Number of LEDs
|RECORD=41|OwnerIndex=125|IndexInSheet=38|OwnerPartId=-1|Location.X=228|Location.Y=321|Color=8388608|FontID=1|IsHidden=T|Text=130°|Name=Viewing Angle
|RECORD=41|OwnerIndex=125|IndexInSheet=39|OwnerPartId=-1|Location.X=228|Location.Y=321|Color=8388608|FontID=1|IsHidden=T|Text=Rectangular|Name=Lens Style
|RECORD=41|OwnerIndex=125|IndexInSheet=40|OwnerPartId=-1|Location.X=228|Location.Y=321|Color=8388608|FontID=1|IsHidden=T|Text=Green|Name=Illumination Color
|RECORD=41|OwnerIndex=125|IndexInSheet=41|OwnerPartId=-1|Location.X=228|Location.Y=321|Color=8388608|FontID=1|IsHidden=T|Text=20mA|Name=Test Current
|RECORD=41|OwnerIndex=125|IndexInSheet=42|OwnerPartId=-1|Location.X=228|Location.Y=321|Color=8388608|FontID=1|IsHidden=T|Text=1608|Name=Case Code (Metric)
|RECORD=41|OwnerIndex=125|IndexInSheet=43|OwnerPartId=-1|Location.X=228|Location.Y=321|Color=8388608|FontID=1|IsHidden=T|Text=Clear|Name=Lens Transparency
|RECORD=41|OwnerIndex=125|IndexInSheet=44|OwnerPartId=-1|Location.X=228|Location.Y=321|Color=8388608|FontID=1|IsHidden=T|Text=35mcd|Name=Luminous Intensity
|RECORD=41|OwnerIndex=125|IndexInSheet=45|OwnerPartId=-1|Location.X=228|Location.Y=321|Color=8388608|FontID=1|IsHidden=T|Text=1|Name=Number of Elements
|RECORD=41|OwnerIndex=125|IndexInSheet=46|OwnerPartId=-1|Location.X=228|Location.Y=321|Color=8388608|FontID=1|IsHidden=T|Text=574nm|Name=Wavelength
|RECORD=34|OwnerIndex=125|IndexInSheet=-1|OwnerPartId=-1|Location.X=246|Location.Y=321|Color=8388608|FontID=1|Text=D22|Name=Designator|ReadOnlyState=1
|RECORD=41|OwnerIndex=125|IndexInSheet=-1|OwnerPartId=1|Location.X=246|Location.Y=277|Color=8388608|FontID=1|Text=LTST-C191KGKT|Name=Comment
|RECORD=44|OwnerIndex=125
|RECORD=45|OwnerIndex=177|IndexInSheet=-1|UseComponentLibrary=T|ModelName=FP-LTST-C191KGKT-MFG|ModelType=PCBLIB|DatafileCount=1|ModelDatafileEntity0=FP-LTST-C191KGKT-MFG|ModelDatafileKind0=PCBLib|IsCurrent=T|DatalinksLocked=T|DatabaseDatalinksLocked=T
|RECORD=46|OwnerIndex=178
|RECORD=48|OwnerIndex=178
|RECORD=1|LibReference=RES|PartCount=2|DisplayModeCount=2|IndexInSheet=44|OwnerPartId=-1|Location.X=210|Location.Y=300|Orientation=2|CurrentPartId=1|SourceLibraryName=Altium Content Vault|TargetFileName=*|AreaColor=11599871|Color=128|PartIDLocked=F|DesignItemId=CMP-2002-08352-1|AllPinCount=2
|RECORD=2|OwnerIndex=181|OwnerPartId=1|OwnerPartDisplayMode=1|FormalType=1|Electrical=4|PinConglomerate=34|PinLength=10|Location.X=190|Location.Y=310|Name=2|Designator=2|PinPropagationDelay=0.000000E+000
|RECORD=2|OwnerIndex=181|OwnerPartId=1|OwnerPartDisplayMode=1|FormalType=1|Electrical=4|PinConglomerate=32|PinLength=10|Location.X=210|Location.Y=310|Name=1|Designator=1|PinPropagationDelay=0.000000E+000
|RECORD=14|OwnerIndex=181|IsNotAccesible=T|IndexInSheet=2|OwnerPartId=1|OwnerPartDisplayMode=1|Location.X=190|Location.Y=306|Corner.X=210|Corner.Y=314|LineWidth=1|Color=16711680|AreaColor=11599871
|RECORD=2|OwnerIndex=181|OwnerPartId=1|FormalType=1|Electrical=4|PinConglomerate=34|PinLength=10|Location.X=190|Location.Y=310|Name=2|Designator=2|PinPropagationDelay=0.000000E+000
|RECORD=2|OwnerIndex=181|OwnerPartId=1|FormalType=1|Electrical=4|PinConglomerate=32|PinLength=10|Location.X=210|Location.Y=310|Name=1|Designator=1|PinPropagationDelay=0.000000E+000
|RECORD=6|OwnerIndex=181|IsNotAccesible=T|IndexInSheet=5|OwnerPartId=1|LineWidth=1|Color=16711680|LocationCount=10|X1=190|Y1=310|X2=194|Y2=310|X3=195|Y3=312|X4=197|Y4=308|X5=199|Y5=312|X6=201|Y6=308|X7=203|Y7=312|X8=205|Y8=308|X9=206|Y9=310|X10=210|Y10=310
|RECORD=41|OwnerIndex=181|IndexInSheet=6|OwnerPartId=-1|Location.X=178|Location.Y=313|Color=8388608|FontID=1|IsHidden=T|Text=Vishay Dale|Name=Manufacturer
|RECORD=41|OwnerIndex=181|IndexInSheet=7|OwnerPartId=-1|Location.X=178|Location.Y=313|Color=8388608|FontID=1|IsHidden=T|Text=CRCW0402200RFKTD|Name=Part Number
|RECORD=34|OwnerIndex=181|IndexInSheet=-1|OwnerPartId=-1|Location.X=189|Location.Y=313|Color=8388608|FontID=1|Text=R122|Name=Designator|ReadOnlyState=1
|RECORD=41|OwnerIndex=181|IndexInSheet=-1|OwnerPartId=-1|Location.X=189|Location.Y=297|Color=8388608|FontID=1|Text=200_1%_0402|Name=Comment
|RECORD=44|OwnerIndex=181
|RECORD=45|OwnerIndex=196|IndexInSheet=-1|Description=Chip Resistor, 2-Leads, Body 1.00x0.50mm, IPC Medium Density|UseComponentLibrary=T|ModelName=RESC1005X40X25NL05T05|ModelType=PCBLIB|DatafileCount=1|ModelDatafileEntity0=RESC1005X40X25NL05T05|ModelDatafileKind0=PCBLib|IsCurrent=T|DatalinksLocked=T|DatabaseDatalinksLocked=T
|RECORD=46|OwnerIndex=197
|RECORD=48|OwnerIndex=197
|RECORD=41|OwnerIndex=199|IndexInSheet=-1|OwnerPartId=-1|Color=8388608|FontID=1|IsHidden=T|Text=2D|Name=Available Preview Images
|RECORD=45|OwnerIndex=196|IndexInSheet=-1|Description=Chip Resistor, 2-Leads, Body 1.00x0.50mm, IPC Low Density|UseComponentLibrary=T|ModelName=RESC1005X40X25ML05T05|ModelType=PCBLIB|DatafileCount=1|ModelDatafileEntity0=RESC1005X40X25ML05T05|ModelDatafileKind0=PCBLib|DatalinksLocked=T|DatabaseDatalinksLocked=T
|RECORD=46|OwnerIndex=201
|RECORD=48|OwnerIndex=201
|RECORD=41|OwnerIndex=203|IndexInSheet=-1|OwnerPartId=-1|Color=8388608|FontID=1|IsHidden=T|Text=2D|Name=Available Preview Images
|RECORD=45|OwnerIndex=196|IndexInSheet=-1|Description=Chip Resistor, 2-Leads, Body 1.00x0.50mm, IPC High Density|UseComponentLibrary=T|ModelName=RESC1005X40X25LL05T05|ModelType=PCBLIB|DatafileCount=1|ModelDatafileEntity0=RESC1005X40X25LL05T05|ModelDatafileKind0=PCBLib|DatalinksLocked=T|DatabaseDatalinksLocked=T
|RECORD=46|OwnerIndex=205
|RECORD=48|OwnerIndex=205
|RECORD=41|OwnerIndex=207|IndexInSheet=-1|OwnerPartId=-1|Color=8388608|FontID=1|IsHidden=T|Text=2D|Name=Available Preview Images
|RECORD=17|IndexInSheet=45|OwnerPartId=-1|ShowNetName=T|Location.X=310|Location.Y=330|Orientation=1|Color=128|FontID=1|Text=+3.3V
|RECORD=17|IndexInSheet=46|OwnerPartId=-1|Style=1|ShowNetName=T|Location.X=170|Location.Y=410|Orientation=2|Color=255|FontID=1|Text=DIP_SW_UART_SEL|IsCrossSheetConnector=T
|RECORD=1|LibReference=8706943c75ba83719d021d2fdc84c58|ComponentDescription=LED GREEN CLEAR SMD|PartCount=2|DisplayModeCount=1|IndexInSheet=47|OwnerPartId=-1|Location.X=290|Location.Y=410|Orientation=2|CurrentPartId=1|LibraryPath=*|SourceLibraryName=Altium Content Vault|TargetFileName=*|AreaColor=11599871|Color=128|PartIDLocked=T|DesignItemId=CMP-2000-05198-2|AllPinCount=2
|RECORD=2|OwnerIndex=211|OwnerPartId=1|Electrical=4|PinConglomerate=48|PinLength=20|Location.X=270|Location.Y=410|Name=A|Designator=2|PinPropagationDelay=0.000000E+000
|RECORD=2|OwnerIndex=211|OwnerPartId=1|Electrical=4|PinConglomerate=50|PinLength=20|Location.X=250|Location.Y=410|Name=C|Designator=1|PinPropagationDelay=0.000000E+000
|RECORD=13|OwnerIndex=211|IsNotAccesible=T|IndexInSheet=2|OwnerPartId=1|Location.X=270|Location.Y=400|Corner.X=270|Corner.Y=420|LineWidth=1|Color=16711680
|RECORD=13|OwnerIndex=211|IsNotAccesible=T|IndexInSheet=3|OwnerPartId=1|Location.X=250|Location.Y=400|Corner.X=250|Corner.Y=420|LineWidth=1|Color=16711680
|RECORD=13|OwnerIndex=211|IsNotAccesible=T|IndexInSheet=4|OwnerPartId=1|Location.X=270|Location.Y=400|Corner.X=250|Corner.Y=410|LineWidth=1|Color=16711680
|RECORD=13|OwnerIndex=211|IsNotAccesible=T|IndexInSheet=5|OwnerPartId=1|Location.X=270|Location.Y=420|Corner.X=250|Corner.Y=410|LineWidth=1|Color=16711680
|RECORD=13|OwnerIndex=211|IsNotAccesible=T|IndexInSheet=6|OwnerPartId=1|Location.X=265|Location.Y=398|Corner.X=255|Corner.Y=388|LineWidth=1|Color=16711680
|RECORD=13|OwnerIndex=211|IsNotAccesible=T|IndexInSheet=7|OwnerPartId=1|Location.X=255|Location.Y=388|Corner.X=260|Corner.Y=388|LineWidth=1|Color=16711680
|RECORD=13|OwnerIndex=211|IsNotAccesible=T|IndexInSheet=8|OwnerPartId=1|Location.X=255|Location.Y=388|Corner.X=255|Corner.Y=393|LineWidth=1|Color=16711680
|RECORD=13|OwnerIndex=211|IsNotAccesible=T|IndexInSheet=9|OwnerPartId=1|Location.X=258|Location.Y=402|Corner.X=248|Corner.Y=392|LineWidth=1|Color=16711680
|RECORD=13|OwnerIndex=211|IsNotAccesible=T|IndexInSheet=10|OwnerPartId=1|Location.X=248|Location.Y=392|Corner.X=253|Corner.Y=392|LineWidth=1|Color=16711680
|RECORD=13|OwnerIndex=211|IsNotAccesible=T|IndexInSheet=11|OwnerPartId=1|Location.X=248|Location.Y=392|Corner.X=248|Corner.Y=397|LineWidth=1|Color=16711680
|RECORD=13|OwnerIndex=211|IsNotAccesible=T|IndexInSheet=12|OwnerPartId=1|Location.X=270|Location.Y=410|Corner.X=273|Corner.Y=410|LineWidth=1|Color=16711680
|RECORD=13|OwnerIndex=211|IsNotAccesible=T|IndexInSheet=13|OwnerPartId=1|Location.X=250|Location.Y=410|Corner.X=247|Corner.Y=410|LineWidth=1|Color=16711680
|RECORD=41|OwnerIndex=211|IndexInSheet=14|OwnerPartId=-1|Location.X=228|Location.Y=421|Color=8388608|FontID=1|IsHidden=T|Text=0.8mm|Name=Width
|RECORD=41|OwnerIndex=211|IndexInSheet=15|OwnerPartId=-1|Location.X=228|Location.Y=421|Color=8388608|FontID=1|IsHidden=T|Text=0603|Name=Case Code (Imperial)
|RECORD=41|OwnerIndex=211|IndexInSheet=16|OwnerPartId=-1|Location.X=228|Location.Y=421|Color=8388608|FontID=1|IsHidden=T|Text=2|Name=Number of Pins
|RECORD=41|OwnerIndex=211|IndexInSheet=17|OwnerPartId=-1|Location.X=228|Location.Y=421|Color=8388608|FontID=1|IsHidden=T|Text=75mW|Name=Max Power Dissipation
|RECORD=41|OwnerIndex=211|IndexInSheet=18|OwnerPartId=-1|Location.X=228|Location.Y=421|Color=8388608|FontID=1|IsHidden=T|Text=30mA|Name=Forward Current
|RECORD=41|OwnerIndex=211|IndexInSheet=19|OwnerPartId=-1|Location.X=228|Location.Y=421|Color=8388608|FontID=1|IsHidden=T|Text=Lead Free|Name=Lead Free
|RECORD=41|OwnerIndex=211|IndexInSheet=20|OwnerPartId=-1|Location.X=228|Location.Y=421|Color=8388608|FontID=1|IsHidden=T|Text=5V|Name=Reverse Voltage
|RECORD=41|OwnerIndex=211|IndexInSheet=21|OwnerPartId=-1|Location.X=228|Location.Y=421|Color=8388608|FontID=1|IsHidden=T|Text=Colorless|Name=Lens Color
|RECORD=41|OwnerIndex=211|IndexInSheet=22|OwnerPartId=-1|Location.X=228|Location.Y=421|Color=8388608|FontID=1|IsHidden=T|Text=2V|Name=Forward Voltage
|RECORD=41|OwnerIndex=211|IndexInSheet=23|OwnerPartId=-1|Location.X=228|Location.Y=421|Color=8388608|FontID=1|IsHidden=T|Text=Tape and Reel|Name=Packaging
|RECORD=41|OwnerIndex=211|IndexInSheet=24|OwnerPartId=-1|Location.X=228|Location.Y=421|Color=8388608|FontID=1|IsHidden=T|Text=1|Name=Package Quantity
|RECORD=41|OwnerIndex=211|IndexInSheet=25|OwnerPartId=-1|Location.X=228|Location.Y=421|Color=8388608|FontID=1|IsHidden=T|Text=-55°C|Name=Min Operating Temperature
|RECORD=41|OwnerIndex=211|IndexInSheet=26|OwnerPartId=-1|Location.X=228|Location.Y=421|Color=8388608|FontID=1|IsHidden=T|Text=0603|Name=Case/Package
|RECORD=41|OwnerIndex=211|IndexInSheet=27|OwnerPartId=-1|Location.X=228|Location.Y=421|Color=8388608|FontID=1|IsHidden=T|Text=1.6mm|Name=Length
|RECORD=41|OwnerIndex=211|IndexInSheet=28|OwnerPartId=-1|Location.X=228|Location.Y=421|Color=8388608|FontID=1|IsHidden=T|Text=75mW|Name=Power Dissipation
|RECORD=41|OwnerIndex=211|IndexInSheet=29|OwnerPartId=-1|Location.X=228|Location.Y=421|Color=8388608|FontID=1|IsHidden=T|Text=571nm|Name=Dominant Wavelength
|RECORD=41|OwnerIndex=211|IndexInSheet=30|OwnerPartId=-1|Location.X=228|Location.Y=421|Color=8388608|FontID=1|IsHidden=T|Text=0.8mm|Name=Depth
|RECORD=41|OwnerIndex=211|IndexInSheet=31|OwnerPartId=-1|Location.X=228|Location.Y=421|Color=8388608|FontID=1|IsHidden=T|Text=No|Name=Radiation Hardening
|RECORD=41|OwnerIndex=211|IndexInSheet=32|OwnerPartId=-1|Location.X=228|Location.Y=421|Color=8388608|FontID=1|IsHidden=T|Text=Surface Mount|Name=Mount
|RECORD=41|OwnerIndex=211|IndexInSheet=33|OwnerPartId=-1|Location.X=228|Location.Y=421|Color=8388608|FontID=1|IsHidden=T|Text=85°C|Name=Max Operating Temperature
|RECORD=41|OwnerIndex=211|IndexInSheet=34|OwnerPartId=-1|Location.X=228|Location.Y=421|Color=8388608|FontID=1|IsHidden=T|Text=Green|Name=Color
|RECORD=41|OwnerIndex=211|IndexInSheet=35|OwnerPartId=-1|Location.X=228|Location.Y=421|Color=8388608|FontID=1|IsHidden=T|Text=75mW|Name=Power Rating
|RECORD=41|OwnerIndex=211|IndexInSheet=36|OwnerPartId=-1|Location.X=228|Location.Y=421|Color=8388608|FontID=1|IsHidden=T|Text=0.55mm|Name=Height
|RECORD=41|OwnerIndex=211|IndexInSheet=37|OwnerPartId=-1|Location.X=228|Location.Y=421|Color=8388608|FontID=1|IsHidden=T|Text=1|Name=Number of LEDs
|RECORD=41|OwnerIndex=211|IndexInSheet=38|OwnerPartId=-1|Location.X=228|Location.Y=421|Color=8388608|FontID=1|IsHidden=T|Text=130°|Name=Viewing Angle
|RECORD=41|OwnerIndex=211|IndexInSheet=39|OwnerPartId=-1|Location.X=228|Location.Y=421|Color=8388608|FontID=1|IsHidden=T|Text=Rectangular|Name=Lens Style
|RECORD=41|OwnerIndex=211|IndexInSheet=40|OwnerPartId=-1|Location.X=228|Location.Y=421|Color=8388608|FontID=1|IsHidden=T|Text=Green|Name=Illumination Color
|RECORD=41|OwnerIndex=211|IndexInSheet=41|OwnerPartId=-1|Location.X=228|Location.Y=421|Color=8388608|FontID=1|IsHidden=T|Text=20mA|Name=Test Current
|RECORD=41|OwnerIndex=211|IndexInSheet=42|OwnerPartId=-1|Location.X=228|Location.Y=421|Color=8388608|FontID=1|IsHidden=T|Text=1608|Name=Case Code (Metric)
|RECORD=41|OwnerIndex=211|IndexInSheet=43|OwnerPartId=-1|Location.X=228|Location.Y=421|Color=8388608|FontID=1|IsHidden=T|Text=Clear|Name=Lens Transparency
|RECORD=41|OwnerIndex=211|IndexInSheet=44|OwnerPartId=-1|Location.X=228|Location.Y=421|Color=8388608|FontID=1|IsHidden=T|Text=35mcd|Name=Luminous Intensity
|RECORD=41|OwnerIndex=211|IndexInSheet=45|OwnerPartId=-1|Location.X=228|Location.Y=421|Color=8388608|FontID=1|IsHidden=T|Text=1|Name=Number of Elements
|RECORD=41|OwnerIndex=211|IndexInSheet=46|OwnerPartId=-1|Location.X=228|Location.Y=421|Color=8388608|FontID=1|IsHidden=T|Text=574nm|Name=Wavelength
|RECORD=34|OwnerIndex=211|IndexInSheet=-1|OwnerPartId=-1|Location.X=246|Location.Y=421|Color=8388608|FontID=1|Text=D21|Name=Designator|ReadOnlyState=1
|RECORD=41|OwnerIndex=211|IndexInSheet=-1|OwnerPartId=1|Location.X=246|Location.Y=377|Color=8388608|FontID=1|Text=LTST-C191KGKT|Name=Comment
|RECORD=44|OwnerIndex=211
|RECORD=45|OwnerIndex=263|IndexInSheet=-1|UseComponentLibrary=T|ModelName=FP-LTST-C191KGKT-MFG|ModelType=PCBLIB|DatafileCount=1|ModelDatafileEntity0=FP-LTST-C191KGKT-MFG|ModelDatafileKind0=PCBLib|IsCurrent=T|DatalinksLocked=T|DatabaseDatalinksLocked=T
|RECORD=46|OwnerIndex=264
|RECORD=48|OwnerIndex=264
|RECORD=1|LibReference=RES|PartCount=2|DisplayModeCount=2|IndexInSheet=48|OwnerPartId=-1|Location.X=210|Location.Y=400|Orientation=2|CurrentPartId=1|SourceLibraryName=Altium Content Vault|TargetFileName=*|AreaColor=11599871|Color=128|PartIDLocked=F|DesignItemId=CMP-2002-08352-1|AllPinCount=2
|RECORD=2|OwnerIndex=267|OwnerPartId=1|OwnerPartDisplayMode=1|FormalType=1|Electrical=4|PinConglomerate=34|PinLength=10|Location.X=190|Location.Y=410|Name=2|Designator=2|PinPropagationDelay=0.000000E+000
|RECORD=2|OwnerIndex=267|OwnerPartId=1|OwnerPartDisplayMode=1|FormalType=1|Electrical=4|PinConglomerate=32|PinLength=10|Location.X=210|Location.Y=410|Name=1|Designator=1|PinPropagationDelay=0.000000E+000
|RECORD=14|OwnerIndex=267|IsNotAccesible=T|IndexInSheet=2|OwnerPartId=1|OwnerPartDisplayMode=1|Location.X=190|Location.Y=406|Corner.X=210|Corner.Y=414|LineWidth=1|Color=16711680|AreaColor=11599871
|RECORD=2|OwnerIndex=267|OwnerPartId=1|FormalType=1|Electrical=4|PinConglomerate=34|PinLength=10|Location.X=190|Location.Y=410|Name=2|Designator=2|PinPropagationDelay=0.000000E+000
|RECORD=2|OwnerIndex=267|OwnerPartId=1|FormalType=1|Electrical=4|PinConglomerate=32|PinLength=10|Location.X=210|Location.Y=410|Name=1|Designator=1|PinPropagationDelay=0.000000E+000
|RECORD=6|OwnerIndex=267|IsNotAccesible=T|IndexInSheet=5|OwnerPartId=1|LineWidth=1|Color=16711680|LocationCount=10|X1=190|Y1=410|X2=194|Y2=410|X3=195|Y3=412|X4=197|Y4=408|X5=199|Y5=412|X6=201|Y6=408|X7=203|Y7=412|X8=205|Y8=408|X9=206|Y9=410|X10=210|Y10=410
|RECORD=41|OwnerIndex=267|IndexInSheet=6|OwnerPartId=-1|Location.X=178|Location.Y=413|Color=8388608|FontID=1|IsHidden=T|Text=Vishay Dale|Name=Manufacturer
|RECORD=41|OwnerIndex=267|IndexInSheet=7|OwnerPartId=-1|Location.X=178|Location.Y=413|Color=8388608|FontID=1|IsHidden=T|Text=CRCW0402200RFKTD|Name=Part Number
|RECORD=34|OwnerIndex=267|IndexInSheet=-1|OwnerPartId=-1|Location.X=189|Location.Y=413|Color=8388608|FontID=1|Text=R112|Name=Designator|ReadOnlyState=1
|RECORD=41|OwnerIndex=267|IndexInSheet=-1|OwnerPartId=-1|Location.X=189|Location.Y=397|Color=8388608|FontID=1|Text=200_1%_0402|Name=Comment
|RECORD=44|OwnerIndex=267
|RECORD=45|OwnerIndex=282|IndexInSheet=-1|Description=Chip Resistor, 2-Leads, Body 1.00x0.50mm, IPC Medium Density|UseComponentLibrary=T|ModelName=RESC1005X40X25NL05T05|ModelType=PCBLIB|DatafileCount=1|ModelDatafileEntity0=RESC1005X40X25NL05T05|ModelDatafileKind0=PCBLib|IsCurrent=T|DatalinksLocked=T|DatabaseDatalinksLocked=T
|RECORD=46|OwnerIndex=283
|RECORD=48|OwnerIndex=283
|RECORD=41|OwnerIndex=285|IndexInSheet=-1|OwnerPartId=-1|Color=8388608|FontID=1|IsHidden=T|Text=2D|Name=Available Preview Images
|RECORD=45|OwnerIndex=282|IndexInSheet=-1|Description=Chip Resistor, 2-Leads, Body 1.00x0.50mm, IPC Low Density|UseComponentLibrary=T|ModelName=RESC1005X40X25ML05T05|ModelType=PCBLIB|DatafileCount=1|ModelDatafileEntity0=RESC1005X40X25ML05T05|ModelDatafileKind0=PCBLib|DatalinksLocked=T|DatabaseDatalinksLocked=T
|RECORD=46|OwnerIndex=287
|RECORD=48|OwnerIndex=287
|RECORD=41|OwnerIndex=289|IndexInSheet=-1|OwnerPartId=-1|Color=8388608|FontID=1|IsHidden=T|Text=2D|Name=Available Preview Images
|RECORD=45|OwnerIndex=282|IndexInSheet=-1|Description=Chip Resistor, 2-Leads, Body 1.00x0.50mm, IPC High Density|UseComponentLibrary=T|ModelName=RESC1005X40X25LL05T05|ModelType=PCBLIB|DatafileCount=1|ModelDatafileEntity0=RESC1005X40X25LL05T05|ModelDatafileKind0=PCBLib|DatalinksLocked=T|DatabaseDatalinksLocked=T
|RECORD=46|OwnerIndex=291
|RECORD=48|OwnerIndex=291
|RECORD=41|OwnerIndex=293|IndexInSheet=-1|OwnerPartId=-1|Color=8388608|FontID=1|IsHidden=T|Text=2D|Name=Available Preview Images
|RECORD=17|IndexInSheet=49|OwnerPartId=-1|ShowNetName=T|Location.X=310|Location.Y=430|Orientation=1|Color=128|FontID=1|Text=+3.3V
|RECORD=17|IndexInSheet=50|OwnerPartId=-1|Style=1|ShowNetName=T|Location.X=170|Location.Y=200|Orientation=2|Color=255|FontID=1|Text=DIP_SW_MACSER_SEL|IsCrossSheetConnector=T
|RECORD=1|LibReference=8706943c75ba83719d021d2fdc84c58|ComponentDescription=LED GREEN CLEAR SMD|PartCount=2|DisplayModeCount=1|IndexInSheet=51|OwnerPartId=-1|Location.X=290|Location.Y=200|Orientation=2|CurrentPartId=1|LibraryPath=*|SourceLibraryName=Altium Content Vault|TargetFileName=*|AreaColor=11599871|Color=128|PartIDLocked=T|DesignItemId=CMP-2000-05198-2|AllPinCount=2
|RECORD=2|OwnerIndex=297|OwnerPartId=1|Electrical=4|PinConglomerate=48|PinLength=20|Location.X=270|Location.Y=200|Name=A|Designator=2|PinPropagationDelay=0.000000E+000
|RECORD=2|OwnerIndex=297|OwnerPartId=1|Electrical=4|PinConglomerate=50|PinLength=20|Location.X=250|Location.Y=200|Name=C|Designator=1|PinPropagationDelay=0.000000E+000
|RECORD=13|OwnerIndex=297|IsNotAccesible=T|IndexInSheet=2|OwnerPartId=1|Location.X=270|Location.Y=190|Corner.X=270|Corner.Y=210|LineWidth=1|Color=16711680
|RECORD=13|OwnerIndex=297|IsNotAccesible=T|IndexInSheet=3|OwnerPartId=1|Location.X=250|Location.Y=190|Corner.X=250|Corner.Y=210|LineWidth=1|Color=16711680
|RECORD=13|OwnerIndex=297|IsNotAccesible=T|IndexInSheet=4|OwnerPartId=1|Location.X=270|Location.Y=190|Corner.X=250|Corner.Y=200|LineWidth=1|Color=16711680
|RECORD=13|OwnerIndex=297|IsNotAccesible=T|IndexInSheet=5|OwnerPartId=1|Location.X=270|Location.Y=210|Corner.X=250|Corner.Y=200|LineWidth=1|Color=16711680
|RECORD=13|OwnerIndex=297|IsNotAccesible=T|IndexInSheet=6|OwnerPartId=1|Location.X=265|Location.Y=188|Corner.X=255|Corner.Y=178|LineWidth=1|Color=16711680
|RECORD=13|OwnerIndex=297|IsNotAccesible=T|IndexInSheet=7|OwnerPartId=1|Location.X=255|Location.Y=178|Corner.X=260|Corner.Y=178|LineWidth=1|Color=16711680
|RECORD=13|OwnerIndex=297|IsNotAccesible=T|IndexInSheet=8|OwnerPartId=1|Location.X=255|Location.Y=178|Corner.X=255|Corner.Y=183|LineWidth=1|Color=16711680
|RECORD=13|OwnerIndex=297|IsNotAccesible=T|IndexInSheet=9|OwnerPartId=1|Location.X=258|Location.Y=192|Corner.X=248|Corner.Y=182|LineWidth=1|Color=16711680
|RECORD=13|OwnerIndex=297|IsNotAccesible=T|IndexInSheet=10|OwnerPartId=1|Location.X=248|Location.Y=182|Corner.X=253|Corner.Y=182|LineWidth=1|Color=16711680
|RECORD=13|OwnerIndex=297|IsNotAccesible=T|IndexInSheet=11|OwnerPartId=1|Location.X=248|Location.Y=182|Corner.X=248|Corner.Y=187|LineWidth=1|Color=16711680
|RECORD=13|OwnerIndex=297|IsNotAccesible=T|IndexInSheet=12|OwnerPartId=1|Location.X=270|Location.Y=200|Corner.X=273|Corner.Y=200|LineWidth=1|Color=16711680
|RECORD=13|OwnerIndex=297|IsNotAccesible=T|IndexInSheet=13|OwnerPartId=1|Location.X=250|Location.Y=200|Corner.X=247|Corner.Y=200|LineWidth=1|Color=16711680
|RECORD=41|OwnerIndex=297|IndexInSheet=14|OwnerPartId=-1|Location.X=228|Location.Y=211|Color=8388608|FontID=1|IsHidden=T|Text=0.8mm|Name=Width
|RECORD=41|OwnerIndex=297|IndexInSheet=15|OwnerPartId=-1|Location.X=228|Location.Y=211|Color=8388608|FontID=1|IsHidden=T|Text=0603|Name=Case Code (Imperial)
|RECORD=41|OwnerIndex=297|IndexInSheet=16|OwnerPartId=-1|Location.X=228|Location.Y=211|Color=8388608|FontID=1|IsHidden=T|Text=2|Name=Number of Pins
|RECORD=41|OwnerIndex=297|IndexInSheet=17|OwnerPartId=-1|Location.X=228|Location.Y=211|Color=8388608|FontID=1|IsHidden=T|Text=75mW|Name=Max Power Dissipation
|RECORD=41|OwnerIndex=297|IndexInSheet=18|OwnerPartId=-1|Location.X=228|Location.Y=211|Color=8388608|FontID=1|IsHidden=T|Text=30mA|Name=Forward Current
|RECORD=41|OwnerIndex=297|IndexInSheet=19|OwnerPartId=-1|Location.X=228|Location.Y=211|Color=8388608|FontID=1|IsHidden=T|Text=Lead Free|Name=Lead Free
|RECORD=41|OwnerIndex=297|IndexInSheet=20|OwnerPartId=-1|Location.X=228|Location.Y=211|Color=8388608|FontID=1|IsHidden=T|Text=5V|Name=Reverse Voltage
|RECORD=41|OwnerIndex=297|IndexInSheet=21|OwnerPartId=-1|Location.X=228|Location.Y=211|Color=8388608|FontID=1|IsHidden=T|Text=Colorless|Name=Lens Color
|RECORD=41|OwnerIndex=297|IndexInSheet=22|OwnerPartId=-1|Location.X=228|Location.Y=211|Color=8388608|FontID=1|IsHidden=T|Text=2V|Name=Forward Voltage
|RECORD=41|OwnerIndex=297|IndexInSheet=23|OwnerPartId=-1|Location.X=228|Location.Y=211|Color=8388608|FontID=1|IsHidden=T|Text=Tape and Reel|Name=Packaging
|RECORD=41|OwnerIndex=297|IndexInSheet=24|OwnerPartId=-1|Location.X=228|Location.Y=211|Color=8388608|FontID=1|IsHidden=T|Text=1|Name=Package Quantity
|RECORD=41|OwnerIndex=297|IndexInSheet=25|OwnerPartId=-1|Location.X=228|Location.Y=211|Color=8388608|FontID=1|IsHidden=T|Text=-55°C|Name=Min Operating Temperature
|RECORD=41|OwnerIndex=297|IndexInSheet=26|OwnerPartId=-1|Location.X=228|Location.Y=211|Color=8388608|FontID=1|IsHidden=T|Text=0603|Name=Case/Package
|RECORD=41|OwnerIndex=297|IndexInSheet=27|OwnerPartId=-1|Location.X=228|Location.Y=211|Color=8388608|FontID=1|IsHidden=T|Text=1.6mm|Name=Length
|RECORD=41|OwnerIndex=297|IndexInSheet=28|OwnerPartId=-1|Location.X=228|Location.Y=211|Color=8388608|FontID=1|IsHidden=T|Text=75mW|Name=Power Dissipation
|RECORD=41|OwnerIndex=297|IndexInSheet=29|OwnerPartId=-1|Location.X=228|Location.Y=211|Color=8388608|FontID=1|IsHidden=T|Text=571nm|Name=Dominant Wavelength
|RECORD=41|OwnerIndex=297|IndexInSheet=30|OwnerPartId=-1|Location.X=228|Location.Y=211|Color=8388608|FontID=1|IsHidden=T|Text=0.8mm|Name=Depth
|RECORD=41|OwnerIndex=297|IndexInSheet=31|OwnerPartId=-1|Location.X=228|Location.Y=211|Color=8388608|FontID=1|IsHidden=T|Text=No|Name=Radiation Hardening
|RECORD=41|OwnerIndex=297|IndexInSheet=32|OwnerPartId=-1|Location.X=228|Location.Y=211|Color=8388608|FontID=1|IsHidden=T|Text=Surface Mount|Name=Mount
|RECORD=41|OwnerIndex=297|IndexInSheet=33|OwnerPartId=-1|Location.X=228|Location.Y=211|Color=8388608|FontID=1|IsHidden=T|Text=85°C|Name=Max Operating Temperature
|RECORD=41|OwnerIndex=297|IndexInSheet=34|OwnerPartId=-1|Location.X=228|Location.Y=211|Color=8388608|FontID=1|IsHidden=T|Text=Green|Name=Color
|RECORD=41|OwnerIndex=297|IndexInSheet=35|OwnerPartId=-1|Location.X=228|Location.Y=211|Color=8388608|FontID=1|IsHidden=T|Text=75mW|Name=Power Rating
|RECORD=41|OwnerIndex=297|IndexInSheet=36|OwnerPartId=-1|Location.X=228|Location.Y=211|Color=8388608|FontID=1|IsHidden=T|Text=0.55mm|Name=Height
|RECORD=41|OwnerIndex=297|IndexInSheet=37|OwnerPartId=-1|Location.X=228|Location.Y=211|Color=8388608|FontID=1|IsHidden=T|Text=1|Name=Number of LEDs
|RECORD=41|OwnerIndex=297|IndexInSheet=38|OwnerPartId=-1|Location.X=228|Location.Y=211|Color=8388608|FontID=1|IsHidden=T|Text=130°|Name=Viewing Angle
|RECORD=41|OwnerIndex=297|IndexInSheet=39|OwnerPartId=-1|Location.X=228|Location.Y=211|Color=8388608|FontID=1|IsHidden=T|Text=Rectangular|Name=Lens Style
|RECORD=41|OwnerIndex=297|IndexInSheet=40|OwnerPartId=-1|Location.X=228|Location.Y=211|Color=8388608|FontID=1|IsHidden=T|Text=Green|Name=Illumination Color
|RECORD=41|OwnerIndex=297|IndexInSheet=41|OwnerPartId=-1|Location.X=228|Location.Y=211|Color=8388608|FontID=1|IsHidden=T|Text=20mA|Name=Test Current
|RECORD=41|OwnerIndex=297|IndexInSheet=42|OwnerPartId=-1|Location.X=228|Location.Y=211|Color=8388608|FontID=1|IsHidden=T|Text=1608|Name=Case Code (Metric)
|RECORD=41|OwnerIndex=297|IndexInSheet=43|OwnerPartId=-1|Location.X=228|Location.Y=211|Color=8388608|FontID=1|IsHidden=T|Text=Clear|Name=Lens Transparency
|RECORD=41|OwnerIndex=297|IndexInSheet=44|OwnerPartId=-1|Location.X=228|Location.Y=211|Color=8388608|FontID=1|IsHidden=T|Text=35mcd|Name=Luminous Intensity
|RECORD=41|OwnerIndex=297|IndexInSheet=45|OwnerPartId=-1|Location.X=228|Location.Y=211|Color=8388608|FontID=1|IsHidden=T|Text=1|Name=Number of Elements
|RECORD=41|OwnerIndex=297|IndexInSheet=46|OwnerPartId=-1|Location.X=228|Location.Y=211|Color=8388608|FontID=1|IsHidden=T|Text=574nm|Name=Wavelength
|RECORD=34|OwnerIndex=297|IndexInSheet=-1|OwnerPartId=-1|Location.X=246|Location.Y=211|Color=8388608|FontID=1|Text=D24|Name=Designator|ReadOnlyState=1
|RECORD=41|OwnerIndex=297|IndexInSheet=-1|OwnerPartId=1|Location.X=246|Location.Y=167|Color=8388608|FontID=1|Text=LTST-C191KGKT|Name=Comment
|RECORD=44|OwnerIndex=297
|RECORD=45|OwnerIndex=349|IndexInSheet=-1|UseComponentLibrary=T|ModelName=FP-LTST-C191KGKT-MFG|ModelType=PCBLIB|DatafileCount=1|ModelDatafileEntity0=FP-LTST-C191KGKT-MFG|ModelDatafileKind0=PCBLib|IsCurrent=T|DatalinksLocked=T|DatabaseDatalinksLocked=T
|RECORD=46|OwnerIndex=350
|RECORD=48|OwnerIndex=350
|RECORD=1|LibReference=RES|PartCount=2|DisplayModeCount=2|IndexInSheet=52|OwnerPartId=-1|Location.X=210|Location.Y=190|Orientation=2|CurrentPartId=1|SourceLibraryName=Altium Content Vault|TargetFileName=*|AreaColor=11599871|Color=128|PartIDLocked=F|DesignItemId=CMP-2002-08352-1|AllPinCount=2
|RECORD=2|OwnerIndex=353|OwnerPartId=1|OwnerPartDisplayMode=1|FormalType=1|Electrical=4|PinConglomerate=34|PinLength=10|Location.X=190|Location.Y=200|Name=2|Designator=2|PinPropagationDelay=0.000000E+000
|RECORD=2|OwnerIndex=353|OwnerPartId=1|OwnerPartDisplayMode=1|FormalType=1|Electrical=4|PinConglomerate=32|PinLength=10|Location.X=210|Location.Y=200|Name=1|Designator=1|PinPropagationDelay=0.000000E+000
|RECORD=14|OwnerIndex=353|IsNotAccesible=T|IndexInSheet=2|OwnerPartId=1|OwnerPartDisplayMode=1|Location.X=190|Location.Y=196|Corner.X=210|Corner.Y=204|LineWidth=1|Color=16711680|AreaColor=11599871
|RECORD=2|OwnerIndex=353|OwnerPartId=1|FormalType=1|Electrical=4|PinConglomerate=34|PinLength=10|Location.X=190|Location.Y=200|Name=2|Designator=2|PinPropagationDelay=0.000000E+000
|RECORD=2|OwnerIndex=353|OwnerPartId=1|FormalType=1|Electrical=4|PinConglomerate=32|PinLength=10|Location.X=210|Location.Y=200|Name=1|Designator=1|PinPropagationDelay=0.000000E+000
|RECORD=6|OwnerIndex=353|IsNotAccesible=T|IndexInSheet=5|OwnerPartId=1|LineWidth=1|Color=16711680|LocationCount=10|X1=190|Y1=200|X2=194|Y2=200|X3=195|Y3=202|X4=197|Y4=198|X5=199|Y5=202|X6=201|Y6=198|X7=203|Y7=202|X8=205|Y8=198|X9=206|Y9=200|X10=210|Y10=200
|RECORD=41|OwnerIndex=353|IndexInSheet=6|OwnerPartId=-1|Location.X=178|Location.Y=203|Color=8388608|FontID=1|IsHidden=T|Text=Vishay Dale|Name=Manufacturer
|RECORD=41|OwnerIndex=353|IndexInSheet=7|OwnerPartId=-1|Location.X=178|Location.Y=203|Color=8388608|FontID=1|IsHidden=T|Text=CRCW0402200RFKTD|Name=Part Number
|RECORD=34|OwnerIndex=353|IndexInSheet=-1|OwnerPartId=-1|Location.X=189|Location.Y=203|Color=8388608|FontID=1|Text=R125|Name=Designator|ReadOnlyState=1
|RECORD=41|OwnerIndex=353|IndexInSheet=-1|OwnerPartId=-1|Location.X=189|Location.Y=187|Color=8388608|FontID=1|Text=200_1%_0402|Name=Comment
|RECORD=44|OwnerIndex=353
|RECORD=45|OwnerIndex=368|IndexInSheet=-1|Description=Chip Resistor, 2-Leads, Body 1.00x0.50mm, IPC Medium Density|UseComponentLibrary=T|ModelName=RESC1005X40X25NL05T05|ModelType=PCBLIB|DatafileCount=1|ModelDatafileEntity0=RESC1005X40X25NL05T05|ModelDatafileKind0=PCBLib|IsCurrent=T|DatalinksLocked=T|DatabaseDatalinksLocked=T
|RECORD=46|OwnerIndex=369
|RECORD=48|OwnerIndex=369
|RECORD=41|OwnerIndex=371|IndexInSheet=-1|OwnerPartId=-1|Color=8388608|FontID=1|IsHidden=T|Text=2D|Name=Available Preview Images
|RECORD=45|OwnerIndex=368|IndexInSheet=-1|Description=Chip Resistor, 2-Leads, Body 1.00x0.50mm, IPC Low Density|UseComponentLibrary=T|ModelName=RESC1005X40X25ML05T05|ModelType=PCBLIB|DatafileCount=1|ModelDatafileEntity0=RESC1005X40X25ML05T05|ModelDatafileKind0=PCBLib|DatalinksLocked=T|DatabaseDatalinksLocked=T
|RECORD=46|OwnerIndex=373
|RECORD=48|OwnerIndex=373
|RECORD=41|OwnerIndex=375|IndexInSheet=-1|OwnerPartId=-1|Color=8388608|FontID=1|IsHidden=T|Text=2D|Name=Available Preview Images
|RECORD=45|OwnerIndex=368|IndexInSheet=-1|Description=Chip Resistor, 2-Leads, Body 1.00x0.50mm, IPC High Density|UseComponentLibrary=T|ModelName=RESC1005X40X25LL05T05|ModelType=PCBLIB|DatafileCount=1|ModelDatafileEntity0=RESC1005X40X25LL05T05|ModelDatafileKind0=PCBLib|DatalinksLocked=T|DatabaseDatalinksLocked=T
|RECORD=46|OwnerIndex=377
|RECORD=48|OwnerIndex=377
|RECORD=41|OwnerIndex=379|IndexInSheet=-1|OwnerPartId=-1|Color=8388608|FontID=1|IsHidden=T|Text=2D|Name=Available Preview Images
|RECORD=17|IndexInSheet=53|OwnerPartId=-1|ShowNetName=T|Location.X=310|Location.Y=220|Orientation=1|Color=128|FontID=1|Text=+3.3V
|RECORD=4|IndexInSheet=54|OwnerPartId=-1|Location.X=120|Location.Y=250|Color=8388608|FontID=1|Text=MACSER = 0 for I2C to MAC, 1 for UART to MAC
|RECORD=1|LibReference=12a319ab100cd6cfe745e35972674f5|ComponentDescription=IC SWITCH SPDT DUAL 12UQFN|PartCount=2|DisplayModeCount=1|IndexInSheet=55|OwnerPartId=-1|Location.X=920|Location.Y=770|CurrentPartId=1|LibraryPath=*|SourceLibraryName=Altium Content Vault|TargetFileName=*|AreaColor=11599871|Color=128|PartIDLocked=T|DesignItemId=CMP-04892-000114-1|AllPinCount=12
|RECORD=14|OwnerIndex=383|IsNotAccesible=T|OwnerPartId=1|Location.X=940|Location.Y=610|Corner.X=1040|Corner.Y=780|LineWidth=1|Color=128|AreaColor=11599871|IsSolid=T
|RECORD=2|OwnerIndex=383|OwnerPartId=1|Electrical=7|PinConglomerate=58|PinLength=20|Location.X=940|Location.Y=770|Name=VCC|Designator=9|PinName_PositionConglomerate=16|Name_CustomFontID=1|PinDesignator_PositionConglomerate=16|Designator_CustomFontID=1|PinPropagationDelay=0.000000E+000
|RECORD=2|OwnerIndex=383|OwnerPartId=1|PinConglomerate=58|PinLength=20|Location.X=940|Location.Y=670|Name=SEL1|Designator=1|PinName_PositionConglomerate=16|Name_CustomFontID=1|PinDesignator_PositionConglomerate=16|Designator_CustomFontID=1|PinPropagationDelay=0.000000E+000
|RECORD=2|OwnerIndex=383|OwnerPartId=1|PinConglomerate=58|PinLength=20|Location.X=940|Location.Y=660|Name=SEL2|Designator=5|PinName_PositionConglomerate=16|Name_CustomFontID=1|PinDesignator_PositionConglomerate=16|Designator_CustomFontID=1|PinPropagationDelay=0.000000E+000
|RECORD=2|OwnerIndex=383|OwnerPartId=1|Electrical=4|PinConglomerate=58|PinLength=20|Location.X=940|Location.Y=730|Name=NO1|Designator=2|PinName_PositionConglomerate=16|Name_CustomFontID=1|PinDesignator_PositionConglomerate=16|Designator_CustomFontID=1|PinPropagationDelay=0.000000E+000
|RECORD=2|OwnerIndex=383|OwnerPartId=1|Electrical=4|PinConglomerate=58|PinLength=20|Location.X=940|Location.Y=690|Name=NO2|Designator=4|PinName_PositionConglomerate=16|Name_CustomFontID=1|PinDesignator_PositionConglomerate=16|Designator_CustomFontID=1|PinPropagationDelay=0.000000E+000
|RECORD=2|OwnerIndex=383|OwnerPartId=1|Electrical=4|PinConglomerate=56|PinLength=20|Location.X=1040|Location.Y=750|Name=COM1|Designator=11|PinName_PositionConglomerate=16|Name_CustomFontID=1|PinDesignator_PositionConglomerate=16|Designator_CustomFontID=1|PinPropagationDelay=0.000000E+000
|RECORD=2|OwnerIndex=383|OwnerPartId=1|Electrical=4|PinConglomerate=56|PinLength=20|Location.X=1040|Location.Y=710|Name=COM2|Designator=7|PinName_PositionConglomerate=16|Name_CustomFontID=1|PinDesignator_PositionConglomerate=16|Designator_CustomFontID=1|PinPropagationDelay=0.000000E+000
|RECORD=2|OwnerIndex=383|OwnerPartId=1|Electrical=3|PinConglomerate=58|PinLength=20|Location.X=940|Location.Y=620|Name=F\L\T\|Designator=12|PinName_PositionConglomerate=16|Name_CustomFontID=1|PinDesignator_PositionConglomerate=16|Designator_CustomFontID=1|PinPropagationDelay=0.000000E+000
|RECORD=2|OwnerIndex=383|OwnerPartId=1|PinConglomerate=58|PinLength=20|Location.X=940|Location.Y=640|Name=O\E\|Designator=6|PinName_PositionConglomerate=16|Name_CustomFontID=1|PinDesignator_PositionConglomerate=16|Designator_CustomFontID=1|PinPropagationDelay=0.000000E+000
|RECORD=2|OwnerIndex=383|OwnerPartId=1|Electrical=4|PinConglomerate=58|PinLength=20|Location.X=940|Location.Y=750|Name=NC1|Designator=10|PinName_PositionConglomerate=16|Name_CustomFontID=1|PinDesignator_PositionConglomerate=16|Designator_CustomFontID=1|PinPropagationDelay=0.000000E+000
|RECORD=2|OwnerIndex=383|OwnerPartId=1|Electrical=4|PinConglomerate=58|PinLength=20|Location.X=940|Location.Y=710|Name=NC2|Designator=8|PinName_PositionConglomerate=16|Name_CustomFontID=1|PinDesignator_PositionConglomerate=16|Designator_CustomFontID=1|PinPropagationDelay=0.000000E+000
|RECORD=2|OwnerIndex=383|OwnerPartId=1|Electrical=7|PinConglomerate=56|PinLength=20|Location.X=1040|Location.Y=620|Name=GND|Designator=3|PinName_PositionConglomerate=16|Name_CustomFontID=1|PinDesignator_PositionConglomerate=16|Designator_CustomFontID=1|PinPropagationDelay=0.000000E+000
|RECORD=41|OwnerIndex=383|IndexInSheet=13|OwnerPartId=-1|Location.X=918|Location.Y=780|Color=8388608|FontID=1|IsHidden=T|Text=12|Name=Number of Pins
|RECORD=41|OwnerIndex=383|IndexInSheet=14|OwnerPartId=-1|Location.X=918|Location.Y=780|Color=8388608|FontID=1|IsHidden=T|Text=2|Name=Number of Circuits
|RECORD=41|OwnerIndex=383|IndexInSheet=15|OwnerPartId=-1|Location.X=918|Location.Y=780|Color=8388608|FontID=1|IsHidden=T|Text=-40°C|Name=Min Operating Temperature
|RECORD=41|OwnerIndex=383|IndexInSheet=16|OwnerPartId=-1|Location.X=918|Location.Y=780|Color=8388608|FontID=1|IsHidden=T|Text=Yes|Name=RoHS Compliant
|RECORD=41|OwnerIndex=383|IndexInSheet=17|OwnerPartId=-1|Location.X=918|Location.Y=780|Color=8388608|FontID=1|IsHidden=T|Text=1.2GHz|Name=-3db Bandwidth
|RECORD=41|OwnerIndex=383|IndexInSheet=18|OwnerPartId=-1|Location.X=918|Location.Y=780|Color=8388608|FontID=1|IsHidden=T|Text=125°C|Name=Max Operating Temperature
|RECORD=41|OwnerIndex=383|IndexInSheet=19|OwnerPartId=-1|Location.X=918|Location.Y=780|Color=8388608|FontID=1|IsHidden=T|Text=2|Name=Number of Channels
|RECORD=41|OwnerIndex=383|IndexInSheet=20|OwnerPartId=-1|Location.X=918|Location.Y=780|Color=8388608|FontID=1|IsHidden=T|Text=18R|Name=On-State Resistance
|RECORD=41|OwnerIndex=383|IndexInSheet=21|OwnerPartId=-1|Location.X=918|Location.Y=780|Color=8388608|FontID=1|IsHidden=T|Text=Tape and Reel|Name=Packaging
|RECORD=34|OwnerIndex=383|IndexInSheet=-1|OwnerPartId=-1|Location.X=940|Location.Y=780|Color=8388608|FontID=1|Text=U26|Name=Designator|ReadOnlyState=1
|RECORD=41|OwnerIndex=383|IndexInSheet=-1|OwnerPartId=1|Location.X=940|Location.Y=600|Color=8388608|FontID=1|Text=TMUX1072RUTR|Name=Comment
|RECORD=44|OwnerIndex=383
|RECORD=45|OwnerIndex=420|IndexInSheet=-1|UseComponentLibrary=T|ModelName=FP-RUT0012A-MFG|ModelType=PCBLIB|DatafileCount=1|ModelDatafileEntity0=FP-RUT0012A-MFG|ModelDatafileKind0=PCBLib|IsCurrent=T|DatalinksLocked=T|DatabaseDatalinksLocked=T
|RECORD=46|OwnerIndex=421
|RECORD=48|OwnerIndex=421
|RECORD=17|IndexInSheet=56|OwnerPartId=-1|Style=4|ShowNetName=T|Location.X=900|Location.Y=610|Orientation=3|Color=128|FontID=1|Text=GND
|RECORD=1|LibReference=b4654b650e69147ec39a6b967a45e02|ComponentDescription=General Purpose Ceramic Capacitor, 0402, 100nF, 10%, X7R, 15%, 25V|PartCount=2|DisplayModeCount=1|IndexInSheet=57|OwnerPartId=-1|Location.X=860|Location.Y=800|CurrentPartId=1|LibraryPath=*|SourceLibraryName=Altium Content Vault|TargetFileName=*|AreaColor=11599871|Color=128|PartIDLocked=T|DesignItemId=CMP-2008-02519-2|AllPinCount=2
|RECORD=2|OwnerIndex=425|OwnerPartId=1|Electrical=4|PinConglomerate=49|PinLength=7|Location.X=860|Location.Y=793|Name=1|Designator=1|PinPropagationDelay=0.000000E+000
|RECORD=2|OwnerIndex=425|OwnerPartId=1|Electrical=4|PinConglomerate=51|PinLength=6|Location.X=860|Location.Y=786|Name=2|Designator=2|PinPropagationDelay=0.000000E+000
|RECORD=13|OwnerIndex=425|IsNotAccesible=T|IndexInSheet=2|OwnerPartId=1|Location.X=870|Location.Y=793|Corner.X=850|Corner.Y=793|LineWidth=1|Color=16711680
|RECORD=13|OwnerIndex=425|IsNotAccesible=T|IndexInSheet=3|OwnerPartId=1|Location.X=870|Location.Y=787|Corner.X=850|Corner.Y=787|LineWidth=1|Color=16711680
|RECORD=13|OwnerIndex=425|IsNotAccesible=T|IndexInSheet=4|OwnerPartId=1|Location.X=860|Location.Y=793|Corner.X=860|Corner.Y=796|LineWidth=1|Color=16711680
|RECORD=13|OwnerIndex=425|IsNotAccesible=T|IndexInSheet=5|OwnerPartId=1|Location.X=860|Location.Y=786|Corner.X=860|Corner.Y=785|LineWidth=1|Color=16711680
|RECORD=41|OwnerIndex=425|IndexInSheet=6|OwnerPartId=-1|Location.X=849|Location.Y=802|Color=8388608|FontID=1|IsHidden=T|Text=1|Name=Package Quantity
|RECORD=41|OwnerIndex=425|IndexInSheet=7|OwnerPartId=-1|Location.X=849|Location.Y=802|Color=8388608|FontID=1|IsHidden=T|Text=100nF|Name=Capacitance
|RECORD=41|OwnerIndex=425|IndexInSheet=8|OwnerPartId=-1|Location.X=849|Location.Y=802|Color=8388608|FontID=1|IsHidden=T|Text=-55°C|Name=Min Operating Temperature
|RECORD=41|OwnerIndex=425|IndexInSheet=9|OwnerPartId=-1|Location.X=849|Location.Y=802|Color=8388608|FontID=1|IsHidden=T|Text=25V|Name=Voltage
|RECORD=41|OwnerIndex=425|IndexInSheet=10|OwnerPartId=-1|Location.X=849|Location.Y=802|Color=8388608|FontID=1|IsHidden=T|Text=25V|Name=Voltage Rating
|RECORD=41|OwnerIndex=425|IndexInSheet=11|OwnerPartId=-1|Location.X=849|Location.Y=802|Color=8388608|FontID=1|IsHidden=T|Text=Flat|Name=Construction
|RECORD=41|OwnerIndex=425|IndexInSheet=12|OwnerPartId=-1|Location.X=849|Location.Y=802|Color=8388608|FontID=1|IsHidden=T|Text=125°C|Name=Max Operating Temperature
|RECORD=41|OwnerIndex=425|IndexInSheet=13|OwnerPartId=-1|Location.X=849|Location.Y=802|Color=8388608|FontID=1|IsHidden=T|Text=No|Name=Radiation Hardening
|RECORD=41|OwnerIndex=425|IndexInSheet=14|OwnerPartId=-1|Location.X=849|Location.Y=802|Color=8388608|FontID=1|IsHidden=T|Text=0.5mm|Name=Depth
|RECORD=41|OwnerIndex=425|IndexInSheet=15|OwnerPartId=-1|Location.X=849|Location.Y=802|Color=8388608|FontID=1|IsHidden=T|Text=0.022inch|Name=Thickness
|RECORD=41|OwnerIndex=425|IndexInSheet=16|OwnerPartId=-1|Location.X=849|Location.Y=802|Color=8388608|FontID=1|IsHidden=T|Text=25V|Name=Voltage Rating (DC)
|RECORD=41|OwnerIndex=425|IndexInSheet=17|OwnerPartId=-1|Location.X=849|Location.Y=802|Color=8388608|FontID=1|IsHidden=T|Text=2|Name=Number of Pins
|RECORD=41|OwnerIndex=425|IndexInSheet=18|OwnerPartId=-1|Location.X=849|Location.Y=802|Color=8388608|FontID=1|IsHidden=T|Text=Lead Free|Name=Lead Free
|RECORD=41|OwnerIndex=425|IndexInSheet=19|OwnerPartId=-1|Location.X=849|Location.Y=802|Color=8388608|FontID=1|IsHidden=T|Text=-|Name=Series
|RECORD=41|OwnerIndex=425|IndexInSheet=20|OwnerPartId=-1|Location.X=849|Location.Y=802|Color=8388608|FontID=1|IsHidden=T|Text=No SVHC|Name=REACH SVHC
|RECORD=41|OwnerIndex=425|IndexInSheet=21|OwnerPartId=-1|Location.X=849|Location.Y=802|Color=8388608|FontID=1|IsHidden=T|Text=1mm|Name=Length
|RECORD=41|OwnerIndex=425|IndexInSheet=22|OwnerPartId=-1|Location.X=849|Location.Y=802|Color=8388608|FontID=1|IsHidden=T|Text=X7R|Name=Dielectric
|RECORD=41|OwnerIndex=425|IndexInSheet=23|OwnerPartId=-1|Location.X=849|Location.Y=802|Color=8388608|FontID=1|IsHidden=T|Text=Yes|Name=RoHS Compliant
|RECORD=41|OwnerIndex=425|IndexInSheet=24|OwnerPartId=-1|Location.X=849|Location.Y=802|Color=8388608|FontID=1|IsHidden=T|Text=Surface Mount|Name=Mount
|RECORD=41|OwnerIndex=425|IndexInSheet=25|OwnerPartId=-1|Location.X=849|Location.Y=802|Color=8388608|FontID=1|IsHidden=T|Text=Tape and Reel|Name=Packaging
|RECORD=41|OwnerIndex=425|IndexInSheet=26|OwnerPartId=-1|Location.X=849|Location.Y=802|Color=8388608|FontID=1|IsHidden=T|Text=0402|Name=Case/Package
|RECORD=41|OwnerIndex=425|IndexInSheet=27|OwnerPartId=-1|Location.X=849|Location.Y=802|Color=8388608|FontID=1|IsHidden=T|Text=0402|Name=Case Code (Imperial)
|RECORD=41|OwnerIndex=425|IndexInSheet=28|OwnerPartId=-1|Location.X=849|Location.Y=802|Color=8388608|FontID=1|IsHidden=T|Text=SMD/SMT|Name=Termination
|RECORD=41|OwnerIndex=425|IndexInSheet=29|OwnerPartId=-1|Location.X=849|Location.Y=802|Color=8388608|FontID=1|IsHidden=T|Text=0.02inch|Name=Width
|RECORD=41|OwnerIndex=425|IndexInSheet=30|OwnerPartId=-1|Location.X=849|Location.Y=802|Color=8388608|FontID=1|IsHidden=T|Text=1005|Name=Case Code (Metric)
|RECORD=41|OwnerIndex=425|IndexInSheet=31|OwnerPartId=-1|Location.X=849|Location.Y=802|Color=8388608|FontID=1|IsHidden=T|Text=10%|Name=Tolerance
|RECORD=34|OwnerIndex=425|IndexInSheet=-1|OwnerPartId=-1|Location.X=850|Location.Y=780|Orientation=1|Color=8388608|FontID=2|Text=C69|Name=Designator|ReadOnlyState=1
|RECORD=41|OwnerIndex=425|IndexInSheet=-1|OwnerPartId=1|Location.X=880|Location.Y=765|Orientation=1|Color=8388608|FontID=2|Text=0.1uF_25V_0402|Name=Comment
|RECORD=44|OwnerIndex=425
|RECORD=45|OwnerIndex=462|IndexInSheet=-1|UseComponentLibrary=T|ModelName=FP-0402-L_1_0_1-W_0_5_0_1-IPC_C|ModelType=PCBLIB|DatafileCount=1|ModelDatafileEntity0=FP-0402-L_1_0_1-W_0_5_0_1-IPC_C|ModelDatafileKind0=PCBLib|IsCurrent=T|DatalinksLocked=T|DatabaseDatalinksLocked=T
|RECORD=46|OwnerIndex=463
|RECORD=48|OwnerIndex=463
|RECORD=45|OwnerIndex=462|IndexInSheet=-1|UseComponentLibrary=T|ModelName=FP-0402-L_1_0_1-W_0_5_0_1-IPC_B|ModelType=PCBLIB|DatafileCount=1|ModelDatafileEntity0=FP-0402-L_1_0_1-W_0_5_0_1-IPC_B|ModelDatafileKind0=PCBLib|DatalinksLocked=T|DatabaseDatalinksLocked=T
|RECORD=46|OwnerIndex=466
|RECORD=48|OwnerIndex=466
|RECORD=45|OwnerIndex=462|IndexInSheet=-1|UseComponentLibrary=T|ModelName=FP-0402-L_1_0_1-W_0_5_0_1-MFG|ModelType=PCBLIB|DatafileCount=1|ModelDatafileEntity0=FP-0402-L_1_0_1-W_0_5_0_1-MFG|ModelDatafileKind0=PCBLib|DatalinksLocked=T|DatabaseDatalinksLocked=T
|RECORD=46|OwnerIndex=469
|RECORD=48|OwnerIndex=469
|RECORD=45|OwnerIndex=462|IndexInSheet=-1|UseComponentLibrary=T|ModelName=FP-0402-L_1_0_1-W_0_5_0_1-IPC_A|ModelType=PCBLIB|DatafileCount=1|ModelDatafileEntity0=FP-0402-L_1_0_1-W_0_5_0_1-IPC_A|ModelDatafileKind0=PCBLib|DatalinksLocked=T|DatabaseDatalinksLocked=T
|RECORD=46|OwnerIndex=472
|RECORD=48|OwnerIndex=472
|RECORD=17|IndexInSheet=58|OwnerPartId=-1|ShowNetName=T|Location.X=800|Location.Y=850|Orientation=1|Color=128|FontID=1|Text=+3.3V
|RECORD=17|IndexInSheet=59|OwnerPartId=-1|Style=4|ShowNetName=T|Location.X=860|Location.Y=770|Orientation=3|Color=128|FontID=1|Text=GND
|RECORD=4|IndexInSheet=60|OwnerPartId=-1|Location.X=930|Location.Y=830|Color=8388608|FontID=1|Text=Connect UART to MAC otherwise
|RECORD=17|IndexInSheet=61|OwnerPartId=-1|ShowNetName=T|Location.X=810|Location.Y=670|Orientation=2|Color=255|FontID=1|Text=DIP_SW_MACSER_SEL|IsCrossSheetConnector=T
|RECORD=17|IndexInSheet=62|OwnerPartId=-1|Style=4|ShowNetName=T|Location.X=1070|Location.Y=610|Orientation=3|Color=128|FontID=1|Text=GND
|RECORD=1|LibReference=RES|PartCount=2|DisplayModeCount=2|IndexInSheet=63|OwnerPartId=-1|Location.X=790|Location.Y=760|CurrentPartId=1|SourceLibraryName=Altium Content Vault|TargetFileName=*|AreaColor=11599871|Color=128|PartIDLocked=F|DesignItemId=CMP-2002-08434-1|AllPinCount=2
|RECORD=2|OwnerIndex=480|OwnerPartId=1|OwnerPartDisplayMode=1|FormalType=1|Electrical=4|PinConglomerate=32|PinLength=10|Location.X=810|Location.Y=750|Name=2|Designator=2|PinPropagationDelay=0.000000E+000
|RECORD=2|OwnerIndex=480|OwnerPartId=1|OwnerPartDisplayMode=1|FormalType=1|Electrical=4|PinConglomerate=34|PinLength=10|Location.X=790|Location.Y=750|Name=1|Designator=1|PinPropagationDelay=0.000000E+000
|RECORD=14|OwnerIndex=480|IsNotAccesible=T|IndexInSheet=2|OwnerPartId=1|OwnerPartDisplayMode=1|Location.X=790|Location.Y=746|Corner.X=810|Corner.Y=754|LineWidth=1|Color=16711680|AreaColor=11599871
|RECORD=2|OwnerIndex=480|OwnerPartId=1|FormalType=1|Electrical=4|PinConglomerate=32|PinLength=10|Location.X=810|Location.Y=750|Name=2|Designator=2|PinPropagationDelay=0.000000E+000
|RECORD=2|OwnerIndex=480|OwnerPartId=1|FormalType=1|Electrical=4|PinConglomerate=34|PinLength=10|Location.X=790|Location.Y=750|Name=1|Designator=1|PinPropagationDelay=0.000000E+000
|RECORD=6|OwnerIndex=480|IsNotAccesible=T|IndexInSheet=5|OwnerPartId=1|LineWidth=1|Color=16711680|LocationCount=10|X1=810|Y1=750|X2=806|Y2=750|X3=805|Y3=748|X4=803|Y4=752|X5=801|Y5=748|X6=799|Y6=752|X7=797|Y7=748|X8=795|Y8=752|X9=794|Y9=750|X10=790|Y10=750
|RECORD=41|OwnerIndex=480|IndexInSheet=6|OwnerPartId=-1|Location.X=778|Location.Y=763|Color=8388608|FontID=1|IsHidden=T|Text=CRCW040227R0FKED|Name=Part Number
|RECORD=41|OwnerIndex=480|IndexInSheet=7|OwnerPartId=-1|Location.X=778|Location.Y=763|Color=8388608|FontID=1|IsHidden=T|Text=Vishay Dale|Name=Manufacturer
|RECORD=34|OwnerIndex=480|IndexInSheet=-1|OwnerPartId=-1|Location.X=770|Location.Y=750|Color=8388608|FontID=1|Text=R76|Name=Designator|ReadOnlyState=1
|RECORD=41|OwnerIndex=480|IndexInSheet=-1|OwnerPartId=-1|Location.X=790|Location.Y=750|Color=8388608|FontID=1|Text=27_1%_0402|Name=Comment
|RECORD=44|OwnerIndex=480
|RECORD=45|OwnerIndex=495|IndexInSheet=-1|Description=Chip Resistor, 2-Leads, Body 1.00x0.50mm, IPC Medium Density|UseComponentLibrary=T|ModelName=RESC1005X40X25NL05T05|ModelType=PCBLIB|DatafileCount=1|ModelDatafileEntity0=RESC1005X40X25NL05T05|ModelDatafileKind0=PCBLib|IsCurrent=T|DatalinksLocked=T|DatabaseDatalinksLocked=T
|RECORD=46|OwnerIndex=496
|RECORD=48|OwnerIndex=496
|RECORD=41|OwnerIndex=498|IndexInSheet=-1|OwnerPartId=-1|Color=8388608|FontID=1|IsHidden=T|Text=2D|Name=Available Preview Images
|RECORD=45|OwnerIndex=495|IndexInSheet=-1|Description=Chip Resistor, 2-Leads, Body 1.00x0.50mm, IPC High Density|UseComponentLibrary=T|ModelName=RESC1005X40X25LL05T05|ModelType=PCBLIB|DatafileCount=1|ModelDatafileEntity0=RESC1005X40X25LL05T05|ModelDatafileKind0=PCBLib|DatalinksLocked=T|DatabaseDatalinksLocked=T
|RECORD=46|OwnerIndex=500
|RECORD=48|OwnerIndex=500
|RECORD=41|OwnerIndex=502|IndexInSheet=-1|OwnerPartId=-1|Color=8388608|FontID=1|IsHidden=T|Text=2D|Name=Available Preview Images
|RECORD=45|OwnerIndex=495|IndexInSheet=-1|Description=Chip Resistor, 2-Leads, Body 1.00x0.50mm, IPC Low Density|UseComponentLibrary=T|ModelName=RESC1005X40X25ML05T05|ModelType=PCBLIB|DatafileCount=1|ModelDatafileEntity0=RESC1005X40X25ML05T05|ModelDatafileKind0=PCBLib|DatalinksLocked=T|DatabaseDatalinksLocked=T
|RECORD=46|OwnerIndex=504
|RECORD=48|OwnerIndex=504
|RECORD=41|OwnerIndex=506|IndexInSheet=-1|OwnerPartId=-1|Color=8388608|FontID=1|IsHidden=T|Text=2D|Name=Available Preview Images
|RECORD=1|LibReference=RES|PartCount=2|DisplayModeCount=2|IndexInSheet=64|OwnerPartId=-1|Location.X=790|Location.Y=720|CurrentPartId=1|SourceLibraryName=Altium Content Vault|TargetFileName=*|AreaColor=11599871|Color=128|PartIDLocked=F|DesignItemId=CMP-2002-08434-1|AllPinCount=2
|RECORD=2|OwnerIndex=508|OwnerPartId=1|OwnerPartDisplayMode=1|FormalType=1|Electrical=4|PinConglomerate=32|PinLength=10|Location.X=810|Location.Y=710|Name=2|Designator=2|PinPropagationDelay=0.000000E+000
|RECORD=2|OwnerIndex=508|OwnerPartId=1|OwnerPartDisplayMode=1|FormalType=1|Electrical=4|PinConglomerate=34|PinLength=10|Location.X=790|Location.Y=710|Name=1|Designator=1|PinPropagationDelay=0.000000E+000
|RECORD=14|OwnerIndex=508|IsNotAccesible=T|IndexInSheet=2|OwnerPartId=1|OwnerPartDisplayMode=1|Location.X=790|Location.Y=706|Corner.X=810|Corner.Y=714|LineWidth=1|Color=16711680|AreaColor=11599871
|RECORD=2|OwnerIndex=508|OwnerPartId=1|FormalType=1|Electrical=4|PinConglomerate=32|PinLength=10|Location.X=810|Location.Y=710|Name=2|Designator=2|PinPropagationDelay=0.000000E+000
|RECORD=2|OwnerIndex=508|OwnerPartId=1|FormalType=1|Electrical=4|PinConglomerate=34|PinLength=10|Location.X=790|Location.Y=710|Name=1|Designator=1|PinPropagationDelay=0.000000E+000
|RECORD=6|OwnerIndex=508|IsNotAccesible=T|IndexInSheet=5|OwnerPartId=1|LineWidth=1|Color=16711680|LocationCount=10|X1=810|Y1=710|X2=806|Y2=710|X3=805|Y3=708|X4=803|Y4=712|X5=801|Y5=708|X6=799|Y6=712|X7=797|Y7=708|X8=795|Y8=712|X9=794|Y9=710|X10=790|Y10=710
|RECORD=41|OwnerIndex=508|IndexInSheet=6|OwnerPartId=-1|Location.X=778|Location.Y=723|Color=8388608|FontID=1|IsHidden=T|Text=CRCW040227R0FKED|Name=Part Number
|RECORD=41|OwnerIndex=508|IndexInSheet=7|OwnerPartId=-1|Location.X=778|Location.Y=723|Color=8388608|FontID=1|IsHidden=T|Text=Vishay Dale|Name=Manufacturer
|RECORD=34|OwnerIndex=508|IndexInSheet=-1|OwnerPartId=-1|Location.X=770|Location.Y=710|Color=8388608|FontID=1|Text=R95|Name=Designator|ReadOnlyState=1
|RECORD=41|OwnerIndex=508|IndexInSheet=-1|OwnerPartId=-1|Location.X=790|Location.Y=710|Color=8388608|FontID=1|Text=27_1%_0402|Name=Comment
|RECORD=44|OwnerIndex=508
|RECORD=45|OwnerIndex=523|IndexInSheet=-1|Description=Chip Resistor, 2-Leads, Body 1.00x0.50mm, IPC Medium Density|UseComponentLibrary=T|ModelName=RESC1005X40X25NL05T05|ModelType=PCBLIB|DatafileCount=1|ModelDatafileEntity0=RESC1005X40X25NL05T05|ModelDatafileKind0=PCBLib|IsCurrent=T|DatalinksLocked=T|DatabaseDatalinksLocked=T
|RECORD=46|OwnerIndex=524
|RECORD=48|OwnerIndex=524
|RECORD=41|OwnerIndex=526|IndexInSheet=-1|OwnerPartId=-1|Color=8388608|FontID=1|IsHidden=T|Text=2D|Name=Available Preview Images
|RECORD=45|OwnerIndex=523|IndexInSheet=-1|Description=Chip Resistor, 2-Leads, Body 1.00x0.50mm, IPC High Density|UseComponentLibrary=T|ModelName=RESC1005X40X25LL05T05|ModelType=PCBLIB|DatafileCount=1|ModelDatafileEntity0=RESC1005X40X25LL05T05|ModelDatafileKind0=PCBLib|DatalinksLocked=T|DatabaseDatalinksLocked=T
|RECORD=46|OwnerIndex=528
|RECORD=48|OwnerIndex=528
|RECORD=41|OwnerIndex=530|IndexInSheet=-1|OwnerPartId=-1|Color=8388608|FontID=1|IsHidden=T|Text=2D|Name=Available Preview Images
|RECORD=45|OwnerIndex=523|IndexInSheet=-1|Description=Chip Resistor, 2-Leads, Body 1.00x0.50mm, IPC Low Density|UseComponentLibrary=T|ModelName=RESC1005X40X25ML05T05|ModelType=PCBLIB|DatafileCount=1|ModelDatafileEntity0=RESC1005X40X25ML05T05|ModelDatafileKind0=PCBLib|DatalinksLocked=T|DatabaseDatalinksLocked=T
|RECORD=46|OwnerIndex=532
|RECORD=48|OwnerIndex=532
|RECORD=41|OwnerIndex=534|IndexInSheet=-1|OwnerPartId=-1|Color=8388608|FontID=1|IsHidden=T|Text=2D|Name=Available Preview Images
|RECORD=1|LibReference=RES|PartCount=2|DisplayModeCount=2|IndexInSheet=65|OwnerPartId=-1|Location.X=790|Location.Y=700|CurrentPartId=1|SourceLibraryName=Altium Content Vault|TargetFileName=*|AreaColor=11599871|Color=128|PartIDLocked=F|DesignItemId=CMP-2002-08434-1|AllPinCount=2
|RECORD=2|OwnerIndex=536|OwnerPartId=1|OwnerPartDisplayMode=1|FormalType=1|Electrical=4|PinConglomerate=32|PinLength=10|Location.X=810|Location.Y=690|Name=2|Designator=2|PinPropagationDelay=0.000000E+000
|RECORD=2|OwnerIndex=536|OwnerPartId=1|OwnerPartDisplayMode=1|FormalType=1|Electrical=4|PinConglomerate=34|PinLength=10|Location.X=790|Location.Y=690|Name=1|Designator=1|PinPropagationDelay=0.000000E+000
|RECORD=14|OwnerIndex=536|IsNotAccesible=T|IndexInSheet=2|OwnerPartId=1|OwnerPartDisplayMode=1|Location.X=790|Location.Y=686|Corner.X=810|Corner.Y=694|LineWidth=1|Color=16711680|AreaColor=11599871
|RECORD=2|OwnerIndex=536|OwnerPartId=1|FormalType=1|Electrical=4|PinConglomerate=32|PinLength=10|Location.X=810|Location.Y=690|Name=2|Designator=2|PinPropagationDelay=0.000000E+000
|RECORD=2|OwnerIndex=536|OwnerPartId=1|FormalType=1|Electrical=4|PinConglomerate=34|PinLength=10|Location.X=790|Location.Y=690|Name=1|Designator=1|PinPropagationDelay=0.000000E+000
|RECORD=6|OwnerIndex=536|IsNotAccesible=T|IndexInSheet=5|OwnerPartId=1|LineWidth=1|Color=16711680|LocationCount=10|X1=810|Y1=690|X2=806|Y2=690|X3=805|Y3=688|X4=803|Y4=692|X5=801|Y5=688|X6=799|Y6=692|X7=797|Y7=688|X8=795|Y8=692|X9=794|Y9=690|X10=790|Y10=690
|RECORD=41|OwnerIndex=536|IndexInSheet=6|OwnerPartId=-1|Location.X=778|Location.Y=703|Color=8388608|FontID=1|IsHidden=T|Text=CRCW040227R0FKED|Name=Part Number
|RECORD=41|OwnerIndex=536|IndexInSheet=7|OwnerPartId=-1|Location.X=778|Location.Y=703|Color=8388608|FontID=1|IsHidden=T|Text=Vishay Dale|Name=Manufacturer
|RECORD=34|OwnerIndex=536|IndexInSheet=-1|OwnerPartId=-1|Location.X=770|Location.Y=690|Color=8388608|FontID=1|Text=R111|Name=Designator|ReadOnlyState=1
|RECORD=41|OwnerIndex=536|IndexInSheet=-1|OwnerPartId=-1|Location.X=790|Location.Y=690|Color=8388608|FontID=1|Text=27_1%_0402|Name=Comment
|RECORD=44|OwnerIndex=536
|RECORD=45|OwnerIndex=551|IndexInSheet=-1|Description=Chip Resistor, 2-Leads, Body 1.00x0.50mm, IPC Medium Density|UseComponentLibrary=T|ModelName=RESC1005X40X25NL05T05|ModelType=PCBLIB|DatafileCount=1|ModelDatafileEntity0=RESC1005X40X25NL05T05|ModelDatafileKind0=PCBLib|IsCurrent=T|DatalinksLocked=T|DatabaseDatalinksLocked=T
|RECORD=46|OwnerIndex=552
|RECORD=48|OwnerIndex=552
|RECORD=41|OwnerIndex=554|IndexInSheet=-1|OwnerPartId=-1|Color=8388608|FontID=1|IsHidden=T|Text=2D|Name=Available Preview Images
|RECORD=45|OwnerIndex=551|IndexInSheet=-1|Description=Chip Resistor, 2-Leads, Body 1.00x0.50mm, IPC High Density|UseComponentLibrary=T|ModelName=RESC1005X40X25LL05T05|ModelType=PCBLIB|DatafileCount=1|ModelDatafileEntity0=RESC1005X40X25LL05T05|ModelDatafileKind0=PCBLib|DatalinksLocked=T|DatabaseDatalinksLocked=T
|RECORD=46|OwnerIndex=556
|RECORD=48|OwnerIndex=556
|RECORD=41|OwnerIndex=558|IndexInSheet=-1|OwnerPartId=-1|Color=8388608|FontID=1|IsHidden=T|Text=2D|Name=Available Preview Images
|RECORD=45|OwnerIndex=551|IndexInSheet=-1|Description=Chip Resistor, 2-Leads, Body 1.00x0.50mm, IPC Low Density|UseComponentLibrary=T|ModelName=RESC1005X40X25ML05T05|ModelType=PCBLIB|DatafileCount=1|ModelDatafileEntity0=RESC1005X40X25ML05T05|ModelDatafileKind0=PCBLib|DatalinksLocked=T|DatabaseDatalinksLocked=T
|RECORD=46|OwnerIndex=560
|RECORD=48|OwnerIndex=560
|RECORD=41|OwnerIndex=562|IndexInSheet=-1|OwnerPartId=-1|Color=8388608|FontID=1|IsHidden=T|Text=2D|Name=Available Preview Images
|RECORD=1|LibReference=RES|PartCount=2|DisplayModeCount=2|IndexInSheet=66|OwnerPartId=-1|Location.X=790|Location.Y=740|CurrentPartId=1|SourceLibraryName=Altium Content Vault|TargetFileName=*|AreaColor=11599871|Color=128|PartIDLocked=F|DesignItemId=CMP-2002-08434-1|AllPinCount=2
|RECORD=2|OwnerIndex=564|OwnerPartId=1|OwnerPartDisplayMode=1|FormalType=1|Electrical=4|PinConglomerate=32|PinLength=10|Location.X=810|Location.Y=730|Name=2|Designator=2|PinPropagationDelay=0.000000E+000
|RECORD=2|OwnerIndex=564|OwnerPartId=1|OwnerPartDisplayMode=1|FormalType=1|Electrical=4|PinConglomerate=34|PinLength=10|Location.X=790|Location.Y=730|Name=1|Designator=1|PinPropagationDelay=0.000000E+000
|RECORD=14|OwnerIndex=564|IsNotAccesible=T|IndexInSheet=2|OwnerPartId=1|OwnerPartDisplayMode=1|Location.X=790|Location.Y=726|Corner.X=810|Corner.Y=734|LineWidth=1|Color=16711680|AreaColor=11599871
|RECORD=2|OwnerIndex=564|OwnerPartId=1|FormalType=1|Electrical=4|PinConglomerate=32|PinLength=10|Location.X=810|Location.Y=730|Name=2|Designator=2|PinPropagationDelay=0.000000E+000
|RECORD=2|OwnerIndex=564|OwnerPartId=1|FormalType=1|Electrical=4|PinConglomerate=34|PinLength=10|Location.X=790|Location.Y=730|Name=1|Designator=1|PinPropagationDelay=0.000000E+000
|RECORD=6|OwnerIndex=564|IsNotAccesible=T|IndexInSheet=5|OwnerPartId=1|LineWidth=1|Color=16711680|LocationCount=10|X1=810|Y1=730|X2=806|Y2=730|X3=805|Y3=728|X4=803|Y4=732|X5=801|Y5=728|X6=799|Y6=732|X7=797|Y7=728|X8=795|Y8=732|X9=794|Y9=730|X10=790|Y10=730
|RECORD=41|OwnerIndex=564|IndexInSheet=6|OwnerPartId=-1|Location.X=778|Location.Y=743|Color=8388608|FontID=1|IsHidden=T|Text=CRCW040227R0FKED|Name=Part Number
|RECORD=41|OwnerIndex=564|IndexInSheet=7|OwnerPartId=-1|Location.X=778|Location.Y=743|Color=8388608|FontID=1|IsHidden=T|Text=Vishay Dale|Name=Manufacturer
|RECORD=34|OwnerIndex=564|IndexInSheet=-1|OwnerPartId=-1|Location.X=770|Location.Y=730|Color=8388608|FontID=1|Text=R94|Name=Designator|ReadOnlyState=1
|RECORD=41|OwnerIndex=564|IndexInSheet=-1|OwnerPartId=-1|Location.X=790|Location.Y=730|Color=8388608|FontID=1|Text=27_1%_0402|Name=Comment
|RECORD=44|OwnerIndex=564
|RECORD=45|OwnerIndex=579|IndexInSheet=-1|Description=Chip Resistor, 2-Leads, Body 1.00x0.50mm, IPC Medium Density|UseComponentLibrary=T|ModelName=RESC1005X40X25NL05T05|ModelType=PCBLIB|DatafileCount=1|ModelDatafileEntity0=RESC1005X40X25NL05T05|ModelDatafileKind0=PCBLib|IsCurrent=T|DatalinksLocked=T|DatabaseDatalinksLocked=T
|RECORD=46|OwnerIndex=580
|RECORD=48|OwnerIndex=580
|RECORD=41|OwnerIndex=582|IndexInSheet=-1|OwnerPartId=-1|Color=8388608|FontID=1|IsHidden=T|Text=2D|Name=Available Preview Images
|RECORD=45|OwnerIndex=579|IndexInSheet=-1|Description=Chip Resistor, 2-Leads, Body 1.00x0.50mm, IPC High Density|UseComponentLibrary=T|ModelName=RESC1005X40X25LL05T05|ModelType=PCBLIB|DatafileCount=1|ModelDatafileEntity0=RESC1005X40X25LL05T05|ModelDatafileKind0=PCBLib|DatalinksLocked=T|DatabaseDatalinksLocked=T
|RECORD=46|OwnerIndex=584
|RECORD=48|OwnerIndex=584
|RECORD=41|OwnerIndex=586|IndexInSheet=-1|OwnerPartId=-1|Color=8388608|FontID=1|IsHidden=T|Text=2D|Name=Available Preview Images
|RECORD=45|OwnerIndex=579|IndexInSheet=-1|Description=Chip Resistor, 2-Leads, Body 1.00x0.50mm, IPC Low Density|UseComponentLibrary=T|ModelName=RESC1005X40X25ML05T05|ModelType=PCBLIB|DatafileCount=1|ModelDatafileEntity0=RESC1005X40X25ML05T05|ModelDatafileKind0=PCBLib|DatalinksLocked=T|DatabaseDatalinksLocked=T
|RECORD=46|OwnerIndex=588
|RECORD=48|OwnerIndex=588
|RECORD=41|OwnerIndex=590|IndexInSheet=-1|OwnerPartId=-1|Color=8388608|FontID=1|IsHidden=T|Text=2D|Name=Available Preview Images
|RECORD=1|LibReference=RES|PartCount=2|DisplayModeCount=2|IndexInSheet=67|OwnerPartId=-1|Location.X=1010|Location.Y=890|CurrentPartId=1|SourceLibraryName=Altium Content Vault|TargetFileName=*|AreaColor=11599871|Color=128|PartIDLocked=F|DesignItemId=CMP-2002-08434-1|AllPinCount=2|ComponentKindVersion2=5
|RECORD=2|OwnerIndex=592|OwnerPartId=1|OwnerPartDisplayMode=1|FormalType=1|Electrical=4|PinConglomerate=32|PinLength=10|Location.X=1030|Location.Y=880|Name=2|Designator=2|PinPropagationDelay=0.000000E+000
|RECORD=2|OwnerIndex=592|OwnerPartId=1|OwnerPartDisplayMode=1|FormalType=1|Electrical=4|PinConglomerate=34|PinLength=10|Location.X=1010|Location.Y=880|Name=1|Designator=1|PinPropagationDelay=0.000000E+000
|RECORD=14|OwnerIndex=592|IsNotAccesible=T|IndexInSheet=2|OwnerPartId=1|OwnerPartDisplayMode=1|Location.X=1010|Location.Y=876|Corner.X=1030|Corner.Y=884|LineWidth=1|Color=16711680|AreaColor=11599871
|RECORD=2|OwnerIndex=592|OwnerPartId=1|FormalType=1|Electrical=4|PinConglomerate=32|PinLength=10|Location.X=1030|Location.Y=880|Name=2|Designator=2|PinPropagationDelay=0.000000E+000
|RECORD=2|OwnerIndex=592|OwnerPartId=1|FormalType=1|Electrical=4|PinConglomerate=34|PinLength=10|Location.X=1010|Location.Y=880|Name=1|Designator=1|PinPropagationDelay=0.000000E+000
|RECORD=6|OwnerIndex=592|IsNotAccesible=T|IndexInSheet=5|OwnerPartId=1|LineWidth=1|Color=16711680|LocationCount=10|X1=1030|Y1=880|X2=1026|Y2=880|X3=1025|Y3=878|X4=1023|Y4=882|X5=1021|Y5=878|X6=1019|Y6=882|X7=1017|Y7=878|X8=1015|Y8=882|X9=1014|Y9=880|X10=1010|Y10=880
|RECORD=41|OwnerIndex=592|IndexInSheet=6|OwnerPartId=-1|Location.X=998|Location.Y=893|Color=8388608|FontID=1|IsHidden=T|Text=CRCW040227R0FKED|Name=Part Number
|RECORD=41|OwnerIndex=592|IndexInSheet=7|OwnerPartId=-1|Location.X=998|Location.Y=893|Color=8388608|FontID=1|IsHidden=T|Text=Vishay Dale|Name=Manufacturer
|RECORD=34|OwnerIndex=592|IndexInSheet=-1|OwnerPartId=-1|Location.X=990|Location.Y=880|Color=8388608|FontID=1|Text=R74|Name=Designator|ReadOnlyState=1
|RECORD=41|OwnerIndex=592|IndexInSheet=-1|OwnerPartId=-1|Location.X=1010|Location.Y=880|Color=8388608|FontID=1|Text=DNI_27_1%_0402|Name=Comment
|RECORD=44|OwnerIndex=592
|RECORD=45|OwnerIndex=607|IndexInSheet=-1|Description=Chip Resistor, 2-Leads, Body 1.00x0.50mm, IPC Medium Density|UseComponentLibrary=T|ModelName=RESC1005X40X25NL05T05|ModelType=PCBLIB|DatafileCount=1|ModelDatafileEntity0=RESC1005X40X25NL05T05|ModelDatafileKind0=PCBLib|IsCurrent=T|DatalinksLocked=T|DatabaseDatalinksLocked=T
|RECORD=46|OwnerIndex=608
|RECORD=48|OwnerIndex=608
|RECORD=41|OwnerIndex=610|IndexInSheet=-1|OwnerPartId=-1|Color=8388608|FontID=1|IsHidden=T|Text=2D|Name=Available Preview Images
|RECORD=45|OwnerIndex=607|IndexInSheet=-1|Description=Chip Resistor, 2-Leads, Body 1.00x0.50mm, IPC High Density|UseComponentLibrary=T|ModelName=RESC1005X40X25LL05T05|ModelType=PCBLIB|DatafileCount=1|ModelDatafileEntity0=RESC1005X40X25LL05T05|ModelDatafileKind0=PCBLib|DatalinksLocked=T|DatabaseDatalinksLocked=T
|RECORD=46|OwnerIndex=612
|RECORD=48|OwnerIndex=612
|RECORD=41|OwnerIndex=614|IndexInSheet=-1|OwnerPartId=-1|Color=8388608|FontID=1|IsHidden=T|Text=2D|Name=Available Preview Images
|RECORD=45|OwnerIndex=607|IndexInSheet=-1|Description=Chip Resistor, 2-Leads, Body 1.00x0.50mm, IPC Low Density|UseComponentLibrary=T|ModelName=RESC1005X40X25ML05T05|ModelType=PCBLIB|DatafileCount=1|ModelDatafileEntity0=RESC1005X40X25ML05T05|ModelDatafileKind0=PCBLib|DatalinksLocked=T|DatabaseDatalinksLocked=T
|RECORD=46|OwnerIndex=616
|RECORD=48|OwnerIndex=616
|RECORD=41|OwnerIndex=618|IndexInSheet=-1|OwnerPartId=-1|Color=8388608|FontID=1|IsHidden=T|Text=2D|Name=Available Preview Images
|RECORD=1|LibReference=RES|PartCount=2|DisplayModeCount=2|IndexInSheet=68|OwnerPartId=-1|Location.X=1010|Location.Y=870|CurrentPartId=1|SourceLibraryName=Altium Content Vault|TargetFileName=*|AreaColor=11599871|Color=128|PartIDLocked=F|DesignItemId=CMP-2002-08434-1|AllPinCount=2|ComponentKindVersion2=5
|RECORD=2|OwnerIndex=620|OwnerPartId=1|OwnerPartDisplayMode=1|FormalType=1|Electrical=4|PinConglomerate=32|PinLength=10|Location.X=1030|Location.Y=860|Name=2|Designator=2|PinPropagationDelay=0.000000E+000
|RECORD=2|OwnerIndex=620|OwnerPartId=1|OwnerPartDisplayMode=1|FormalType=1|Electrical=4|PinConglomerate=34|PinLength=10|Location.X=1010|Location.Y=860|Name=1|Designator=1|PinPropagationDelay=0.000000E+000
|RECORD=14|OwnerIndex=620|IsNotAccesible=T|IndexInSheet=2|OwnerPartId=1|OwnerPartDisplayMode=1|Location.X=1010|Location.Y=856|Corner.X=1030|Corner.Y=864|LineWidth=1|Color=16711680|AreaColor=11599871
|RECORD=2|OwnerIndex=620|OwnerPartId=1|FormalType=1|Electrical=4|PinConglomerate=32|PinLength=10|Location.X=1030|Location.Y=860|Name=2|Designator=2|PinPropagationDelay=0.000000E+000
|RECORD=2|OwnerIndex=620|OwnerPartId=1|FormalType=1|Electrical=4|PinConglomerate=34|PinLength=10|Location.X=1010|Location.Y=860|Name=1|Designator=1|PinPropagationDelay=0.000000E+000
|RECORD=6|OwnerIndex=620|IsNotAccesible=T|IndexInSheet=5|OwnerPartId=1|LineWidth=1|Color=16711680|LocationCount=10|X1=1030|Y1=860|X2=1026|Y2=860|X3=1025|Y3=858|X4=1023|Y4=862|X5=1021|Y5=858|X6=1019|Y6=862|X7=1017|Y7=858|X8=1015|Y8=862|X9=1014|Y9=860|X10=1010|Y10=860
|RECORD=41|OwnerIndex=620|IndexInSheet=6|OwnerPartId=-1|Location.X=998|Location.Y=873|Color=8388608|FontID=1|IsHidden=T|Text=CRCW040227R0FKED|Name=Part Number
|RECORD=41|OwnerIndex=620|IndexInSheet=7|OwnerPartId=-1|Location.X=998|Location.Y=873|Color=8388608|FontID=1|IsHidden=T|Text=Vishay Dale|Name=Manufacturer
|RECORD=34|OwnerIndex=620|IndexInSheet=-1|OwnerPartId=-1|Location.X=990|Location.Y=860|Color=8388608|FontID=1|Text=R75|Name=Designator|ReadOnlyState=1
|RECORD=41|OwnerIndex=620|IndexInSheet=-1|OwnerPartId=-1|Location.X=1010|Location.Y=860|Color=8388608|FontID=1|Text=DNI_27_1%_0402|Name=Comment
|RECORD=44|OwnerIndex=620
|RECORD=45|OwnerIndex=635|IndexInSheet=-1|Description=Chip Resistor, 2-Leads, Body 1.00x0.50mm, IPC Medium Density|UseComponentLibrary=T|ModelName=RESC1005X40X25NL05T05|ModelType=PCBLIB|DatafileCount=1|ModelDatafileEntity0=RESC1005X40X25NL05T05|ModelDatafileKind0=PCBLib|IsCurrent=T|DatalinksLocked=T|DatabaseDatalinksLocked=T
|RECORD=46|OwnerIndex=636
|RECORD=48|OwnerIndex=636
|RECORD=41|OwnerIndex=638|IndexInSheet=-1|OwnerPartId=-1|Color=8388608|FontID=1|IsHidden=T|Text=2D|Name=Available Preview Images
|RECORD=45|OwnerIndex=635|IndexInSheet=-1|Description=Chip Resistor, 2-Leads, Body 1.00x0.50mm, IPC High Density|UseComponentLibrary=T|ModelName=RESC1005X40X25LL05T05|ModelType=PCBLIB|DatafileCount=1|ModelDatafileEntity0=RESC1005X40X25LL05T05|ModelDatafileKind0=PCBLib|DatalinksLocked=T|DatabaseDatalinksLocked=T
|RECORD=46|OwnerIndex=640
|RECORD=48|OwnerIndex=640
|RECORD=41|OwnerIndex=642|IndexInSheet=-1|OwnerPartId=-1|Color=8388608|FontID=1|IsHidden=T|Text=2D|Name=Available Preview Images
|RECORD=45|OwnerIndex=635|IndexInSheet=-1|Description=Chip Resistor, 2-Leads, Body 1.00x0.50mm, IPC Low Density|UseComponentLibrary=T|ModelName=RESC1005X40X25ML05T05|ModelType=PCBLIB|DatafileCount=1|ModelDatafileEntity0=RESC1005X40X25ML05T05|ModelDatafileKind0=PCBLib|DatalinksLocked=T|DatabaseDatalinksLocked=T
|RECORD=46|OwnerIndex=644
|RECORD=48|OwnerIndex=644
|RECORD=41|OwnerIndex=646|IndexInSheet=-1|OwnerPartId=-1|Color=8388608|FontID=1|IsHidden=T|Text=2D|Name=Available Preview Images
|RECORD=17|IndexInSheet=69|OwnerPartId=-1|ShowNetName=T|Location.X=710|Location.Y=750|Orientation=2|Color=255|FontID=1|Text=MAC_I2C_SCL|IsCrossSheetConnector=T
|RECORD=17|IndexInSheet=70|OwnerPartId=-1|ShowNetName=T|Location.X=710|Location.Y=710|Orientation=2|Color=255|FontID=1|Text=MAC_I2C_SDA|IsCrossSheetConnector=T
|RECORD=17|IndexInSheet=71|OwnerPartId=-1|ShowNetName=T|Location.X=1110|Location.Y=750|Color=255|FontID=1|Text=MAC_TX|IsCrossSheetConnector=T
|RECORD=17|IndexInSheet=72|OwnerPartId=-1|ShowNetName=T|Location.X=1110|Location.Y=710|Color=255|FontID=1|Text=MAC_RX|IsCrossSheetConnector=T
|RECORD=17|IndexInSheet=73|OwnerPartId=-1|ShowNetName=T|Location.X=740|Location.Y=690|Orientation=2|Color=255|FontID=1|Text=MAC_FPGA_UART_RX|IsCrossSheetConnector=T
|RECORD=17|IndexInSheet=74|OwnerPartId=-1|ShowNetName=T|Location.X=740|Location.Y=730|Orientation=2|Color=255|FontID=1|Text=FPGA_MAC_UART_TX|IsCrossSheetConnector=T
|RECORD=17|IndexInSheet=75|OwnerPartId=-1|ShowNetName=T|Location.X=970|Location.Y=880|Orientation=2|Color=255|FontID=1|Text=FPGA_MAC_UART_TX|IsCrossSheetConnector=T
|RECORD=17|IndexInSheet=76|OwnerPartId=-1|ShowNetName=T|Location.X=970|Location.Y=860|Orientation=2|Color=255|FontID=1|Text=MAC_FPGA_UART_RX|IsCrossSheetConnector=T
|RECORD=1|LibReference=TI-PCA9546A-VQFN_RGV-16|ComponentDescription=4-Channel I2C and SMBus Multiplexer with Reset Functions, 2.3 to 5.5 V, -40 to 85 degC, 16-pin VQFN (RGV), Green (RoHS & no Sb/Br)|PartCount=2|DisplayModeCount=1|IndexInSheet=77|OwnerPartId=-1|Location.X=930|Location.Y=330|IsMirrored=T|Orientation=2|CurrentPartId=1|LibraryPath=*|SourceLibraryName=Altium Content Vault|TargetFileName=*|AreaColor=11599871|Color=128|PartIDLocked=T|DesignItemId=CMP-0314-00065-2|AllPinCount=17
|RECORD=14|OwnerIndex=656|IsNotAccesible=T|OwnerPartId=1|Location.X=930|Location.Y=330|Corner.X=1010|Corner.Y=480|Color=128|AreaColor=11599871|IsSolid=T
|RECORD=2|OwnerIndex=656|OwnerPartId=1|Description=Active low reset input. Connect to VCC through a pullup resistor, if not used.|FormalType=1|PinConglomerate=58|PinLength=20|Location.X=930|Location.Y=440|Name=R\E\S\E\T\|Designator=1|PinPropagationDelay=0.000000E+000
|RECORD=2|OwnerIndex=656|OwnerPartId=1|Description=Serial data 0. Connect to VCC through a pullup resistor.|FormalType=1|Electrical=1|PinConglomerate=56|PinLength=20|Location.X=1010|Location.Y=350|Name=SD0|Designator=2|PinPropagationDelay=0.000000E+000
|RECORD=2|OwnerIndex=656|OwnerPartId=1|SymBol_InnerEdge=3|Description=Serial clock 0. Connect to VCC through a pullup resistor.|FormalType=1|Electrical=1|PinConglomerate=56|PinLength=20|Location.X=1010|Location.Y=340|Name=SC0|Designator=3|PinPropagationDelay=0.000000E+000
|RECORD=2|OwnerIndex=656|OwnerPartId=1|Description=Serial data 1. Connect to VCC through a pullup resistor.|FormalType=1|Electrical=1|PinConglomerate=56|PinLength=20|Location.X=1010|Location.Y=380|Name=SD1|Designator=4|PinPropagationDelay=0.000000E+000
|RECORD=2|OwnerIndex=656|OwnerPartId=1|SymBol_InnerEdge=3|Description=Serial clock 1. Connect to VCC through a pullup resistor.|FormalType=1|Electrical=1|PinConglomerate=56|PinLength=20|Location.X=1010|Location.Y=370|Name=SC1|Designator=5|PinPropagationDelay=0.000000E+000
|RECORD=2|OwnerIndex=656|OwnerPartId=1|Description=Ground|FormalType=1|Electrical=7|PinConglomerate=56|PinLength=20|Location.X=1010|Location.Y=470|Name=GND|Designator=6|PinPropagationDelay=0.000000E+000
|RECORD=2|OwnerIndex=656|OwnerPartId=1|Description=Serial data 2. Connect to VCC through a pullup resistor.|FormalType=1|Electrical=1|PinConglomerate=56|PinLength=20|Location.X=1010|Location.Y=410|Name=SD2|Designator=7|PinPropagationDelay=0.000000E+000
|RECORD=2|OwnerIndex=656|OwnerPartId=1|SymBol_InnerEdge=3|Description=Serial clock 2. Connect to VCC through a pullup resistor.|FormalType=1|Electrical=1|PinConglomerate=56|PinLength=20|Location.X=1010|Location.Y=400|Name=SC2|Designator=8|PinPropagationDelay=0.000000E+000
|RECORD=2|OwnerIndex=656|OwnerPartId=1|Description=Serial data 3. Connect to VCC through a pullup resistor.|FormalType=1|Electrical=1|PinConglomerate=56|PinLength=20|Location.X=1010|Location.Y=440|Name=SD3|Designator=9|PinPropagationDelay=0.000000E+000
|RECORD=2|OwnerIndex=656|OwnerPartId=1|SymBol_InnerEdge=3|Description=Serial clock 3. Connect to VCC through a pullup resistor.|FormalType=1|Electrical=1|PinConglomerate=56|PinLength=20|Location.X=1010|Location.Y=430|Name=SC3|Designator=10|PinPropagationDelay=0.000000E+000
|RECORD=2|OwnerIndex=656|OwnerPartId=1|Description=Address input 2. Connect directly to VCC or ground.|FormalType=1|PinConglomerate=58|PinLength=20|Location.X=930|Location.Y=390|Name=A2|Designator=11|PinPropagationDelay=0.000000E+000
|RECORD=2|OwnerIndex=656|OwnerPartId=1|SymBol_InnerEdge=3|Description=Serial clock line. Connect to VCC through a pullup resistor.|FormalType=1|Electrical=1|PinConglomerate=58|PinLength=20|Location.X=930|Location.Y=340|Name=SCL|Designator=12|PinPropagationDelay=0.000000E+000
|RECORD=2|OwnerIndex=656|OwnerPartId=1|Description=Serial data line. Connect to VCC through a pullup resistor.|FormalType=1|Electrical=1|PinConglomerate=58|PinLength=20|Location.X=930|Location.Y=350|Name=SDA|Designator=13|PinPropagationDelay=0.000000E+000
|RECORD=2|OwnerIndex=656|OwnerPartId=1|Description=Supply power|FormalType=1|Electrical=7|PinConglomerate=58|PinLength=20|Location.X=930|Location.Y=470|Name=VCC|Designator=14|PinPropagationDelay=0.000000E+000
|RECORD=2|OwnerIndex=656|OwnerPartId=1|Description=Address input 0. Connect directly to VCC or ground.|FormalType=1|PinConglomerate=58|PinLength=20|Location.X=930|Location.Y=370|Name=A0|Designator=15|PinPropagationDelay=0.000000E+000
|RECORD=2|OwnerIndex=656|OwnerPartId=1|Description=Address input 1. Connect directly to VCC or ground.|FormalType=1|PinConglomerate=58|PinLength=20|Location.X=930|Location.Y=380|Name=A1|Designator=16|PinPropagationDelay=0.000000E+000
|RECORD=2|OwnerIndex=656|OwnerPartId=1|Description=Exposed Pad|FormalType=1|Electrical=4|PinConglomerate=56|PinLength=20|Location.X=1010|Location.Y=460|Name=EP|Designator=17|PinPropagationDelay=0.000000E+000
|RECORD=41|OwnerIndex=656|IndexInSheet=18|OwnerPartId=-1|Location.X=908|Location.Y=480|Color=8388608|FontID=1|IsHidden=T|Text=Surface Mount|Name=Mounting Technology|IsMirrored=T
|RECORD=41|OwnerIndex=656|IndexInSheet=19|OwnerPartId=-1|Location.X=908|Location.Y=480|Color=8388608|FontID=1|IsHidden=T|Name=Slave Side I2C Bus Capacitance Supported(pF)|IsMirrored=T
|RECORD=41|OwnerIndex=656|IndexInSheet=20|OwnerPartId=-1|Location.X=908|Location.Y=480|Color=8388608|FontID=1|IsHidden=T|Name=Master Side I2C Bus Capacitance Supported(pF)|IsMirrored=T
|RECORD=41|OwnerIndex=656|IndexInSheet=21|OwnerPartId=-1|Location.X=908|Location.Y=480|Color=8388608|FontID=1|IsHidden=T|Name=Technology Family|IsMirrored=T
|RECORD=41|OwnerIndex=656|IndexInSheet=22|OwnerPartId=-1|Location.X=908|Location.Y=480|Color=8388608|FontID=1|IsHidden=T|Text=Package Specification|Name=ComponentLink2Description|IsMirrored=T
|RECORD=41|OwnerIndex=656|IndexInSheet=23|OwnerPartId=-1|Location.X=908|Location.Y=480|Color=8388608|FontID=1|IsHidden=T|Text=100, 400|Name=fSCLK(Max)(MHz)|IsMirrored=T
|RECORD=41|OwnerIndex=656|IndexInSheet=24|OwnerPartId=-1|Location.X=908|Location.Y=480|Color=8388608|FontID=1|IsHidden=T|Text=SCPS148E|Name=DatasheetVersion|IsMirrored=T
|RECORD=41|OwnerIndex=656|IndexInSheet=25|OwnerPartId=-1|Location.X=908|Location.Y=480|Color=8388608|FontID=1|IsHidden=T|Text=1110 xxx|Name=I2C Address|IsMirrored=T
|RECORD=41|OwnerIndex=656|IndexInSheet=26|OwnerPartId=-1|Location.X=908|Location.Y=480|Color=8388608|FontID=1|IsHidden=T|Text=16-Pin Plastic Quad Flat No-Lead, 4 x 4 mm Body, 0.65 mm Pitch, 2.16 x 2.16 mm Exposed Pad|Name=PackageDescription|IsMirrored=T
|RECORD=41|OwnerIndex=656|IndexInSheet=27|OwnerPartId=-1|Location.X=908|Location.Y=480|Color=8388608|FontID=1|IsHidden=T|Text=2.3|Name=VCC(Min)(V)|IsMirrored=T
|RECORD=41|OwnerIndex=656|IndexInSheet=28|OwnerPartId=-1|Location.X=908|Location.Y=480|Color=8388608|FontID=1|IsHidden=T|Text=Yes|Name=5V Tolerant I/O|IsMirrored=T
|RECORD=41|OwnerIndex=656|IndexInSheet=29|OwnerPartId=-1|Location.X=908|Location.Y=480|Color=8388608|FontID=1|IsHidden=T|Text=revF, Jun-2011|Name=PackageVersion|IsMirrored=T
|RECORD=41|OwnerIndex=656|IndexInSheet=30|OwnerPartId=-1|Location.X=908|Location.Y=480|Color=8388608|FontID=1|IsHidden=T|Text=4|Name=Channel Width|IsMirrored=T
|RECORD=41|OwnerIndex=656|IndexInSheet=31|OwnerPartId=-1|Location.X=908|Location.Y=480|Color=8388608|FontID=1|IsHidden=T|Name=Configuration Registers|IsMirrored=T
|RECORD=41|OwnerIndex=656|IndexInSheet=32|OwnerPartId=-1|Location.X=908|Location.Y=480|Color=8388608|FontID=1|IsHidden=T|Name=Code_JEDEC|IsMirrored=T
|RECORD=41|OwnerIndex=656|IndexInSheet=33|OwnerPartId=-1|Location.X=908|Location.Y=480|Color=8388608|FontID=1|IsHidden=T|Name=On-Chip Power-on-Reset|IsMirrored=T
|RECORD=41|OwnerIndex=656|IndexInSheet=34|OwnerPartId=-1|Location.X=908|Location.Y=480|Color=8388608|FontID=1|IsHidden=T|Name=Interrupt Output|IsMirrored=T
|RECORD=41|OwnerIndex=656|IndexInSheet=35|OwnerPartId=-1|Location.X=908|Location.Y=480|Color=8388608|FontID=3|IsHidden=T|Text=http://www.ti.com/general/docs/lit/getliterature.tsp?genericPartNumber=PCA9546A&fileType=pdf|Name=ComponentLink1URL|IsMirrored=T
|RECORD=41|OwnerIndex=656|IndexInSheet=36|OwnerPartId=-1|Location.X=908|Location.Y=480|Color=8388608|FontID=1|IsHidden=T|Name=Function|IsMirrored=T
|RECORD=41|OwnerIndex=656|IndexInSheet=37|OwnerPartId=-1|Location.X=908|Location.Y=480|Color=8388608|FontID=1|IsHidden=T|Text=5.5|Name=VCC(Max)(V)|IsMirrored=T
|RECORD=41|OwnerIndex=656|IndexInSheet=38|OwnerPartId=-1|Location.X=908|Location.Y=480|Color=8388608|FontID=1|IsHidden=T|Text=Green (RoHS & no Sb/Br)|Name=Eco-Plan|IsMirrored=T
|RECORD=41|OwnerIndex=656|IndexInSheet=39|OwnerPartId=-1|Location.X=908|Location.Y=480|Color=8388608|FontID=1|IsHidden=T|Text=Yes|Name=Reset Input|IsMirrored=T
|RECORD=41|OwnerIndex=656|IndexInSheet=40|OwnerPartId=-1|Location.X=908|Location.Y=480|Color=8388608|FontID=1|IsHidden=T|Name=Rating|IsMirrored=T
|RECORD=41|OwnerIndex=656|IndexInSheet=41|OwnerPartId=-1|Location.X=908|Location.Y=480|Color=8388608|FontID=1|IsHidden=T|Text=2.3 to 5.5|Name=Vcc range(V)|IsMirrored=T
|RECORD=41|OwnerIndex=656|IndexInSheet=42|OwnerPartId=-1|Location.X=908|Location.Y=480|Color=8388608|FontID=1|IsHidden=T|Name=EXP Pin|IsMirrored=T
|RECORD=41|OwnerIndex=656|IndexInSheet=43|OwnerPartId=-1|Location.X=908|Location.Y=480|Color=8388608|FontID=1|IsHidden=T|Text=Texas Instruments|Name=Manufacturer|IsMirrored=T
|RECORD=41|OwnerIndex=656|IndexInSheet=44|OwnerPartId=-1|Location.X=908|Location.Y=480|Color=8388608|FontID=1|IsHidden=T|Name=# of I/Os|IsMirrored=T
|RECORD=41|OwnerIndex=656|IndexInSheet=45|OwnerPartId=-1|Location.X=908|Location.Y=480|Color=8388608|FontID=3|IsHidden=T|Text=http://www.ti.com/litv/pdf/mpds178g|Name=ComponentLink2URL|IsMirrored=T
|RECORD=41|OwnerIndex=656|IndexInSheet=46|OwnerPartId=-1|Location.X=908|Location.Y=480|Color=8388608|FontID=1|IsHidden=T|Text=0.3, 1|Name=tpd max(ns)|IsMirrored=T
|RECORD=41|OwnerIndex=656|IndexInSheet=47|OwnerPartId=-1|Location.X=908|Location.Y=480|Color=8388608|FontID=1|IsHidden=T|Name=No. of Outputs|IsMirrored=T
|RECORD=41|OwnerIndex=656|IndexInSheet=48|OwnerPartId=-1|Location.X=908|Location.Y=480|Color=8388608|FontID=1|IsHidden=T|Name=Low Power|IsMirrored=T
|RECORD=41|OwnerIndex=656|IndexInSheet=49|OwnerPartId=-1|Location.X=908|Location.Y=480|Color=8388608|FontID=1|IsHidden=T|Name=Voltage Nodes(V)|IsMirrored=T
|RECORD=41|OwnerIndex=656|IndexInSheet=50|OwnerPartId=-1|Location.X=908|Location.Y=480|Color=8388608|FontID=1|IsHidden=T|Text=1 to 4|Name=Simultaneously Active Channels|IsMirrored=T
|RECORD=41|OwnerIndex=656|IndexInSheet=51|OwnerPartId=-1|Location.X=908|Location.Y=480|Color=8388608|FontID=1|IsHidden=T|Text=Yes|Name=Open Drain I/O Type|IsMirrored=T
|RECORD=41|OwnerIndex=656|IndexInSheet=52|OwnerPartId=-1|Location.X=908|Location.Y=480|Color=8388608|FontID=1|IsHidden=T|Text=RGV0016A|Name=PackageReference|IsMirrored=T
|RECORD=41|OwnerIndex=656|IndexInSheet=53|OwnerPartId=-1|Location.X=908|Location.Y=480|Color=8388608|FontID=1|IsHidden=T|Text=PCA9546ARGVR|Name=PartNumber|IsMirrored=T
|RECORD=41|OwnerIndex=656|IndexInSheet=54|OwnerPartId=-1|Location.X=908|Location.Y=480|Color=8388608|FontID=1|IsHidden=T|Text=400|Name=Max Frequency(kHz)|IsMirrored=T
|RECORD=41|OwnerIndex=656|IndexInSheet=55|OwnerPartId=-1|Location.X=908|Location.Y=480|Color=8388608|FontID=1|IsHidden=T|Text=I2C Multiplexer, Switch|Name=SubFamily|IsMirrored=T
|RECORD=41|OwnerIndex=656|IndexInSheet=56|OwnerPartId=-1|Location.X=908|Location.Y=480|Color=8388608|FontID=1|IsHidden=T|Name=Push-Pull I/O Type|IsMirrored=T
|RECORD=41|OwnerIndex=656|IndexInSheet=57|OwnerPartId=-1|Location.X=908|Location.Y=480|Color=8388608|FontID=1|IsHidden=T|Text=Datasheet|Name=ComponentLink1Description|IsMirrored=T
|RECORD=41|OwnerIndex=656|IndexInSheet=58|OwnerPartId=-1|Location.X=908|Location.Y=480|Color=8388608|FontID=1|IsHidden=T|Name=Enable Pin|IsMirrored=T
|RECORD=34|OwnerIndex=656|IndexInSheet=-1|OwnerPartId=-1|Location.X=930|Location.Y=480|Color=8388608|FontID=1|Text=U27|Name=Designator|ReadOnlyState=1|IsMirrored=T
|RECORD=41|OwnerIndex=656|IndexInSheet=-1|OwnerPartId=-1|Location.X=930|Location.Y=320|Color=8388608|FontID=1|Text=PCA9546ARGVR|Name=Comment|IsMirrored=T
|RECORD=44|OwnerIndex=656
|RECORD=45|OwnerIndex=735|IndexInSheet=-1|Description=QFN, 16-Leads, Body 4x4mm, Pitch 0.65mm, Thermal Pad 2.16x2.16mm, TI Recommended|UseComponentLibrary=T|ModelName=RGV0016A_V|ModelType=PCBLIB|DatafileCount=1|ModelDatafileEntity0=RGV0016A_V|ModelDatafileKind0=PCBLib|IsCurrent=T|DatalinksLocked=T|DatabaseDatalinksLocked=T
|RECORD=46|OwnerIndex=736
|RECORD=48|OwnerIndex=736
|RECORD=41|OwnerIndex=738|IndexInSheet=-1|OwnerPartId=-1|Color=8388608|FontID=1|IsHidden=T|Text=2D|Name=Available Preview Images
|RECORD=4|IndexInSheet=78|OwnerPartId=-1|Location.X=930|Location.Y=510|Color=8388608|FontID=1|Text=I2C MUX address 7'0x70
|RECORD=1|LibReference=RES|PartCount=2|DisplayModeCount=2|IndexInSheet=79|OwnerPartId=-1|Location.X=810|Location.Y=280|Orientation=1|CurrentPartId=1|SourceLibraryName=Altium Content Vault|TargetFileName=*|AreaColor=11599871|Color=128|PartIDLocked=F|DesignItemId=CMP-2002-08434-1|AllPinCount=2
|RECORD=2|OwnerIndex=741|OwnerPartId=1|OwnerPartDisplayMode=1|FormalType=1|Electrical=4|PinConglomerate=33|PinLength=10|Location.X=820|Location.Y=300|Name=2|Designator=2|PinPropagationDelay=0.000000E+000
|RECORD=2|OwnerIndex=741|OwnerPartId=1|OwnerPartDisplayMode=1|FormalType=1|Electrical=4|PinConglomerate=35|PinLength=10|Location.X=820|Location.Y=280|Name=1|Designator=1|PinPropagationDelay=0.000000E+000
|RECORD=14|OwnerIndex=741|IsNotAccesible=T|IndexInSheet=2|OwnerPartId=1|OwnerPartDisplayMode=1|Location.X=816|Location.Y=280|Corner.X=824|Corner.Y=300|LineWidth=1|Color=16711680|AreaColor=11599871
|RECORD=2|OwnerIndex=741|OwnerPartId=1|FormalType=1|Electrical=4|PinConglomerate=33|PinLength=10|Location.X=820|Location.Y=300|Name=2|Designator=2|PinPropagationDelay=0.000000E+000
|RECORD=2|OwnerIndex=741|OwnerPartId=1|FormalType=1|Electrical=4|PinConglomerate=35|PinLength=10|Location.X=820|Location.Y=280|Name=1|Designator=1|PinPropagationDelay=0.000000E+000
|RECORD=6|OwnerIndex=741|IsNotAccesible=T|IndexInSheet=5|OwnerPartId=1|LineWidth=1|Color=16711680|LocationCount=10|X1=820|Y1=300|X2=820|Y2=296|X3=822|Y3=295|X4=818|Y4=293|X5=822|Y5=291|X6=818|Y6=289|X7=822|Y7=287|X8=818|Y8=285|X9=820|Y9=284|X10=820|Y10=280
|RECORD=41|OwnerIndex=741|IndexInSheet=6|OwnerPartId=-1|Location.X=817|Location.Y=312|Color=8388608|FontID=1|IsHidden=T|Text=CRCW040227R0FKED|Name=Part Number
|RECORD=41|OwnerIndex=741|IndexInSheet=7|OwnerPartId=-1|Location.X=817|Location.Y=312|Color=8388608|FontID=1|IsHidden=T|Text=Vishay Dale|Name=Manufacturer
|RECORD=34|OwnerIndex=741|IndexInSheet=-1|OwnerPartId=-1|Location.X=820|Location.Y=270|Orientation=1|Color=8388608|FontID=2|Text=R126|Name=Designator|ReadOnlyState=1
|RECORD=41|OwnerIndex=741|IndexInSheet=-1|OwnerPartId=-1|Location.X=830|Location.Y=270|Orientation=1|Color=8388608|FontID=2|Text=27_1%_0402|Name=Comment
|RECORD=44|OwnerIndex=741
|RECORD=45|OwnerIndex=756|IndexInSheet=-1|Description=Chip Resistor, 2-Leads, Body 1.00x0.50mm, IPC Medium Density|UseComponentLibrary=T|ModelName=RESC1005X40X25NL05T05|ModelType=PCBLIB|DatafileCount=1|ModelDatafileEntity0=RESC1005X40X25NL05T05|ModelDatafileKind0=PCBLib|IsCurrent=T|DatalinksLocked=T|DatabaseDatalinksLocked=T
|RECORD=46|OwnerIndex=757
|RECORD=48|OwnerIndex=757
|RECORD=41|OwnerIndex=759|IndexInSheet=-1|OwnerPartId=-1|Color=8388608|FontID=1|IsHidden=T|Text=2D|Name=Available Preview Images
|RECORD=45|OwnerIndex=756|IndexInSheet=-1|Description=Chip Resistor, 2-Leads, Body 1.00x0.50mm, IPC High Density|UseComponentLibrary=T|ModelName=RESC1005X40X25LL05T05|ModelType=PCBLIB|DatafileCount=1|ModelDatafileEntity0=RESC1005X40X25LL05T05|ModelDatafileKind0=PCBLib|DatalinksLocked=T|DatabaseDatalinksLocked=T
|RECORD=46|OwnerIndex=761
|RECORD=48|OwnerIndex=761
|RECORD=41|OwnerIndex=763|IndexInSheet=-1|OwnerPartId=-1|Color=8388608|FontID=1|IsHidden=T|Text=2D|Name=Available Preview Images
|RECORD=45|OwnerIndex=756|IndexInSheet=-1|Description=Chip Resistor, 2-Leads, Body 1.00x0.50mm, IPC Low Density|UseComponentLibrary=T|ModelName=RESC1005X40X25ML05T05|ModelType=PCBLIB|DatafileCount=1|ModelDatafileEntity0=RESC1005X40X25ML05T05|ModelDatafileKind0=PCBLib|DatalinksLocked=T|DatabaseDatalinksLocked=T
|RECORD=46|OwnerIndex=765
|RECORD=48|OwnerIndex=765
|RECORD=41|OwnerIndex=767|IndexInSheet=-1|OwnerPartId=-1|Color=8388608|FontID=1|IsHidden=T|Text=2D|Name=Available Preview Images
|RECORD=1|LibReference=RES|PartCount=2|DisplayModeCount=2|IndexInSheet=80|OwnerPartId=-1|Location.X=830|Location.Y=280|Orientation=1|CurrentPartId=1|SourceLibraryName=Altium Content Vault|TargetFileName=*|AreaColor=11599871|Color=128|PartIDLocked=F|DesignItemId=CMP-2002-08434-1|AllPinCount=2
|RECORD=2|OwnerIndex=769|OwnerPartId=1|OwnerPartDisplayMode=1|FormalType=1|Electrical=4|PinConglomerate=33|PinLength=10|Location.X=840|Location.Y=300|Name=2|Designator=2|PinPropagationDelay=0.000000E+000
|RECORD=2|OwnerIndex=769|OwnerPartId=1|OwnerPartDisplayMode=1|FormalType=1|Electrical=4|PinConglomerate=35|PinLength=10|Location.X=840|Location.Y=280|Name=1|Designator=1|PinPropagationDelay=0.000000E+000
|RECORD=14|OwnerIndex=769|IsNotAccesible=T|IndexInSheet=2|OwnerPartId=1|OwnerPartDisplayMode=1|Location.X=836|Location.Y=280|Corner.X=844|Corner.Y=300|LineWidth=1|Color=16711680|AreaColor=11599871
|RECORD=2|OwnerIndex=769|OwnerPartId=1|FormalType=1|Electrical=4|PinConglomerate=33|PinLength=10|Location.X=840|Location.Y=300|Name=2|Designator=2|PinPropagationDelay=0.000000E+000
|RECORD=2|OwnerIndex=769|OwnerPartId=1|FormalType=1|Electrical=4|PinConglomerate=35|PinLength=10|Location.X=840|Location.Y=280|Name=1|Designator=1|PinPropagationDelay=0.000000E+000
|RECORD=6|OwnerIndex=769|IsNotAccesible=T|IndexInSheet=5|OwnerPartId=1|LineWidth=1|Color=16711680|LocationCount=10|X1=840|Y1=300|X2=840|Y2=296|X3=842|Y3=295|X4=838|Y4=293|X5=842|Y5=291|X6=838|Y6=289|X7=842|Y7=287|X8=838|Y8=285|X9=840|Y9=284|X10=840|Y10=280
|RECORD=41|OwnerIndex=769|IndexInSheet=6|OwnerPartId=-1|Location.X=837|Location.Y=312|Color=8388608|FontID=1|IsHidden=T|Text=CRCW040227R0FKED|Name=Part Number
|RECORD=41|OwnerIndex=769|IndexInSheet=7|OwnerPartId=-1|Location.X=837|Location.Y=312|Color=8388608|FontID=1|IsHidden=T|Text=Vishay Dale|Name=Manufacturer
|RECORD=34|OwnerIndex=769|IndexInSheet=-1|OwnerPartId=-1|Location.X=840|Location.Y=270|Orientation=1|Color=8388608|FontID=2|Text=R127|Name=Designator|ReadOnlyState=1
|RECORD=41|OwnerIndex=769|IndexInSheet=-1|OwnerPartId=-1|Location.X=850|Location.Y=270|Orientation=1|Color=8388608|FontID=2|Text=27_1%_0402|Name=Comment
|RECORD=44|OwnerIndex=769
|RECORD=45|OwnerIndex=784|IndexInSheet=-1|Description=Chip Resistor, 2-Leads, Body 1.00x0.50mm, IPC Medium Density|UseComponentLibrary=T|ModelName=RESC1005X40X25NL05T05|ModelType=PCBLIB|DatafileCount=1|ModelDatafileEntity0=RESC1005X40X25NL05T05|ModelDatafileKind0=PCBLib|IsCurrent=T|DatalinksLocked=T|DatabaseDatalinksLocked=T
|RECORD=46|OwnerIndex=785
|RECORD=48|OwnerIndex=785
|RECORD=41|OwnerIndex=787|IndexInSheet=-1|OwnerPartId=-1|Color=8388608|FontID=1|IsHidden=T|Text=2D|Name=Available Preview Images
|RECORD=45|OwnerIndex=784|IndexInSheet=-1|Description=Chip Resistor, 2-Leads, Body 1.00x0.50mm, IPC High Density|UseComponentLibrary=T|ModelName=RESC1005X40X25LL05T05|ModelType=PCBLIB|DatafileCount=1|ModelDatafileEntity0=RESC1005X40X25LL05T05|ModelDatafileKind0=PCBLib|DatalinksLocked=T|DatabaseDatalinksLocked=T
|RECORD=46|OwnerIndex=789
|RECORD=48|OwnerIndex=789
|RECORD=41|OwnerIndex=791|IndexInSheet=-1|OwnerPartId=-1|Color=8388608|FontID=1|IsHidden=T|Text=2D|Name=Available Preview Images
|RECORD=45|OwnerIndex=784|IndexInSheet=-1|Description=Chip Resistor, 2-Leads, Body 1.00x0.50mm, IPC Low Density|UseComponentLibrary=T|ModelName=RESC1005X40X25ML05T05|ModelType=PCBLIB|DatafileCount=1|ModelDatafileEntity0=RESC1005X40X25ML05T05|ModelDatafileKind0=PCBLib|DatalinksLocked=T|DatabaseDatalinksLocked=T
|RECORD=46|OwnerIndex=793
|RECORD=48|OwnerIndex=793
|RECORD=41|OwnerIndex=795|IndexInSheet=-1|OwnerPartId=-1|Color=8388608|FontID=1|IsHidden=T|Text=2D|Name=Available Preview Images
|RECORD=1|LibReference=RES|PartCount=2|DisplayModeCount=2|IndexInSheet=81|OwnerPartId=-1|Location.X=850|Location.Y=280|Orientation=1|CurrentPartId=1|SourceLibraryName=Altium Content Vault|TargetFileName=*|AreaColor=11599871|Color=128|PartIDLocked=F|DesignItemId=CMP-2002-08434-1|AllPinCount=2
|RECORD=2|OwnerIndex=797|OwnerPartId=1|OwnerPartDisplayMode=1|FormalType=1|Electrical=4|PinConglomerate=33|PinLength=10|Location.X=860|Location.Y=300|Name=2|Designator=2|PinPropagationDelay=0.000000E+000
|RECORD=2|OwnerIndex=797|OwnerPartId=1|OwnerPartDisplayMode=1|FormalType=1|Electrical=4|PinConglomerate=35|PinLength=10|Location.X=860|Location.Y=280|Name=1|Designator=1|PinPropagationDelay=0.000000E+000
|RECORD=14|OwnerIndex=797|IsNotAccesible=T|IndexInSheet=2|OwnerPartId=1|OwnerPartDisplayMode=1|Location.X=856|Location.Y=280|Corner.X=864|Corner.Y=300|LineWidth=1|Color=16711680|AreaColor=11599871
|RECORD=2|OwnerIndex=797|OwnerPartId=1|FormalType=1|Electrical=4|PinConglomerate=33|PinLength=10|Location.X=860|Location.Y=300|Name=2|Designator=2|PinPropagationDelay=0.000000E+000
|RECORD=2|OwnerIndex=797|OwnerPartId=1|FormalType=1|Electrical=4|PinConglomerate=35|PinLength=10|Location.X=860|Location.Y=280|Name=1|Designator=1|PinPropagationDelay=0.000000E+000
|RECORD=6|OwnerIndex=797|IsNotAccesible=T|IndexInSheet=5|OwnerPartId=1|LineWidth=1|Color=16711680|LocationCount=10|X1=860|Y1=300|X2=860|Y2=296|X3=862|Y3=295|X4=858|Y4=293|X5=862|Y5=291|X6=858|Y6=289|X7=862|Y7=287|X8=858|Y8=285|X9=860|Y9=284|X10=860|Y10=280
|RECORD=41|OwnerIndex=797|IndexInSheet=6|OwnerPartId=-1|Location.X=857|Location.Y=312|Color=8388608|FontID=1|IsHidden=T|Text=CRCW040227R0FKED|Name=Part Number
|RECORD=41|OwnerIndex=797|IndexInSheet=7|OwnerPartId=-1|Location.X=857|Location.Y=312|Color=8388608|FontID=1|IsHidden=T|Text=Vishay Dale|Name=Manufacturer
|RECORD=34|OwnerIndex=797|IndexInSheet=-1|OwnerPartId=-1|Location.X=860|Location.Y=270|Orientation=1|Color=8388608|FontID=2|Text=R128|Name=Designator|ReadOnlyState=1
|RECORD=41|OwnerIndex=797|IndexInSheet=-1|OwnerPartId=-1|Location.X=870|Location.Y=270|Orientation=1|Color=8388608|FontID=2|Text=27_1%_0402|Name=Comment
|RECORD=44|OwnerIndex=797
|RECORD=45|OwnerIndex=812|IndexInSheet=-1|Description=Chip Resistor, 2-Leads, Body 1.00x0.50mm, IPC Medium Density|UseComponentLibrary=T|ModelName=RESC1005X40X25NL05T05|ModelType=PCBLIB|DatafileCount=1|ModelDatafileEntity0=RESC1005X40X25NL05T05|ModelDatafileKind0=PCBLib|IsCurrent=T|DatalinksLocked=T|DatabaseDatalinksLocked=T
|RECORD=46|OwnerIndex=813
|RECORD=48|OwnerIndex=813
|RECORD=41|OwnerIndex=815|IndexInSheet=-1|OwnerPartId=-1|Color=8388608|FontID=1|IsHidden=T|Text=2D|Name=Available Preview Images
|RECORD=45|OwnerIndex=812|IndexInSheet=-1|Description=Chip Resistor, 2-Leads, Body 1.00x0.50mm, IPC High Density|UseComponentLibrary=T|ModelName=RESC1005X40X25LL05T05|ModelType=PCBLIB|DatafileCount=1|ModelDatafileEntity0=RESC1005X40X25LL05T05|ModelDatafileKind0=PCBLib|DatalinksLocked=T|DatabaseDatalinksLocked=T
|RECORD=46|OwnerIndex=817
|RECORD=48|OwnerIndex=817
|RECORD=41|OwnerIndex=819|IndexInSheet=-1|OwnerPartId=-1|Color=8388608|FontID=1|IsHidden=T|Text=2D|Name=Available Preview Images
|RECORD=45|OwnerIndex=812|IndexInSheet=-1|Description=Chip Resistor, 2-Leads, Body 1.00x0.50mm, IPC Low Density|UseComponentLibrary=T|ModelName=RESC1005X40X25ML05T05|ModelType=PCBLIB|DatafileCount=1|ModelDatafileEntity0=RESC1005X40X25ML05T05|ModelDatafileKind0=PCBLib|DatalinksLocked=T|DatabaseDatalinksLocked=T
|RECORD=46|OwnerIndex=821
|RECORD=48|OwnerIndex=821
|RECORD=41|OwnerIndex=823|IndexInSheet=-1|OwnerPartId=-1|Color=8388608|FontID=1|IsHidden=T|Text=2D|Name=Available Preview Images
|RECORD=17|IndexInSheet=82|OwnerPartId=-1|Style=4|ShowNetName=T|Location.X=820|Location.Y=250|Orientation=3|Color=128|FontID=1|Text=GND
|RECORD=1|LibReference=b4654b650e69147ec39a6b967a45e02|ComponentDescription=General Purpose Ceramic Capacitor, 0402, 100nF, 10%, X7R, 15%, 25V|PartCount=2|DisplayModeCount=1|IndexInSheet=83|OwnerPartId=-1|Location.X=850|Location.Y=500|CurrentPartId=1|LibraryPath=*|SourceLibraryName=Altium Content Vault|TargetFileName=*|AreaColor=11599871|Color=128|PartIDLocked=T|DesignItemId=CMP-2008-02519-2|AllPinCount=2
|RECORD=2|OwnerIndex=826|OwnerPartId=1|Electrical=4|PinConglomerate=49|PinLength=7|Location.X=850|Location.Y=493|Name=1|Designator=1|PinPropagationDelay=0.000000E+000
|RECORD=2|OwnerIndex=826|OwnerPartId=1|Electrical=4|PinConglomerate=51|PinLength=6|Location.X=850|Location.Y=486|Name=2|Designator=2|PinPropagationDelay=0.000000E+000
|RECORD=13|OwnerIndex=826|IsNotAccesible=T|IndexInSheet=2|OwnerPartId=1|Location.X=860|Location.Y=493|Corner.X=840|Corner.Y=493|LineWidth=1|Color=16711680
|RECORD=13|OwnerIndex=826|IsNotAccesible=T|IndexInSheet=3|OwnerPartId=1|Location.X=860|Location.Y=487|Corner.X=840|Corner.Y=487|LineWidth=1|Color=16711680
|RECORD=13|OwnerIndex=826|IsNotAccesible=T|IndexInSheet=4|OwnerPartId=1|Location.X=850|Location.Y=493|Corner.X=850|Corner.Y=496|LineWidth=1|Color=16711680
|RECORD=13|OwnerIndex=826|IsNotAccesible=T|IndexInSheet=5|OwnerPartId=1|Location.X=850|Location.Y=486|Corner.X=850|Corner.Y=485|LineWidth=1|Color=16711680
|RECORD=41|OwnerIndex=826|IndexInSheet=6|OwnerPartId=-1|Location.X=839|Location.Y=502|Color=8388608|FontID=1|IsHidden=T|Text=1|Name=Package Quantity
|RECORD=41|OwnerIndex=826|IndexInSheet=7|OwnerPartId=-1|Location.X=839|Location.Y=502|Color=8388608|FontID=1|IsHidden=T|Text=100nF|Name=Capacitance
|RECORD=41|OwnerIndex=826|IndexInSheet=8|OwnerPartId=-1|Location.X=839|Location.Y=502|Color=8388608|FontID=1|IsHidden=T|Text=-55°C|Name=Min Operating Temperature
|RECORD=41|OwnerIndex=826|IndexInSheet=9|OwnerPartId=-1|Location.X=839|Location.Y=502|Color=8388608|FontID=1|IsHidden=T|Text=25V|Name=Voltage
|RECORD=41|OwnerIndex=826|IndexInSheet=10|OwnerPartId=-1|Location.X=839|Location.Y=502|Color=8388608|FontID=1|IsHidden=T|Text=25V|Name=Voltage Rating
|RECORD=41|OwnerIndex=826|IndexInSheet=11|OwnerPartId=-1|Location.X=839|Location.Y=502|Color=8388608|FontID=1|IsHidden=T|Text=Flat|Name=Construction
|RECORD=41|OwnerIndex=826|IndexInSheet=12|OwnerPartId=-1|Location.X=839|Location.Y=502|Color=8388608|FontID=1|IsHidden=T|Text=125°C|Name=Max Operating Temperature
|RECORD=41|OwnerIndex=826|IndexInSheet=13|OwnerPartId=-1|Location.X=839|Location.Y=502|Color=8388608|FontID=1|IsHidden=T|Text=No|Name=Radiation Hardening
|RECORD=41|OwnerIndex=826|IndexInSheet=14|OwnerPartId=-1|Location.X=839|Location.Y=502|Color=8388608|FontID=1|IsHidden=T|Text=0.5mm|Name=Depth
|RECORD=41|OwnerIndex=826|IndexInSheet=15|OwnerPartId=-1|Location.X=839|Location.Y=502|Color=8388608|FontID=1|IsHidden=T|Text=0.022inch|Name=Thickness
|RECORD=41|OwnerIndex=826|IndexInSheet=16|OwnerPartId=-1|Location.X=839|Location.Y=502|Color=8388608|FontID=1|IsHidden=T|Text=25V|Name=Voltage Rating (DC)
|RECORD=41|OwnerIndex=826|IndexInSheet=17|OwnerPartId=-1|Location.X=839|Location.Y=502|Color=8388608|FontID=1|IsHidden=T|Text=2|Name=Number of Pins
|RECORD=41|OwnerIndex=826|IndexInSheet=18|OwnerPartId=-1|Location.X=839|Location.Y=502|Color=8388608|FontID=1|IsHidden=T|Text=Lead Free|Name=Lead Free
|RECORD=41|OwnerIndex=826|IndexInSheet=19|OwnerPartId=-1|Location.X=839|Location.Y=502|Color=8388608|FontID=1|IsHidden=T|Text=-|Name=Series
|RECORD=41|OwnerIndex=826|IndexInSheet=20|OwnerPartId=-1|Location.X=839|Location.Y=502|Color=8388608|FontID=1|IsHidden=T|Text=No SVHC|Name=REACH SVHC
|RECORD=41|OwnerIndex=826|IndexInSheet=21|OwnerPartId=-1|Location.X=839|Location.Y=502|Color=8388608|FontID=1|IsHidden=T|Text=1mm|Name=Length
|RECORD=41|OwnerIndex=826|IndexInSheet=22|OwnerPartId=-1|Location.X=839|Location.Y=502|Color=8388608|FontID=1|IsHidden=T|Text=X7R|Name=Dielectric
|RECORD=41|OwnerIndex=826|IndexInSheet=23|OwnerPartId=-1|Location.X=839|Location.Y=502|Color=8388608|FontID=1|IsHidden=T|Text=Yes|Name=RoHS Compliant
|RECORD=41|OwnerIndex=826|IndexInSheet=24|OwnerPartId=-1|Location.X=839|Location.Y=502|Color=8388608|FontID=1|IsHidden=T|Text=Surface Mount|Name=Mount
|RECORD=41|OwnerIndex=826|IndexInSheet=25|OwnerPartId=-1|Location.X=839|Location.Y=502|Color=8388608|FontID=1|IsHidden=T|Text=Tape and Reel|Name=Packaging
|RECORD=41|OwnerIndex=826|IndexInSheet=26|OwnerPartId=-1|Location.X=839|Location.Y=502|Color=8388608|FontID=1|IsHidden=T|Text=0402|Name=Case/Package
|RECORD=41|OwnerIndex=826|IndexInSheet=27|OwnerPartId=-1|Location.X=839|Location.Y=502|Color=8388608|FontID=1|IsHidden=T|Text=0402|Name=Case Code (Imperial)
|RECORD=41|OwnerIndex=826|IndexInSheet=28|OwnerPartId=-1|Location.X=839|Location.Y=502|Color=8388608|FontID=1|IsHidden=T|Text=SMD/SMT|Name=Termination
|RECORD=41|OwnerIndex=826|IndexInSheet=29|OwnerPartId=-1|Location.X=839|Location.Y=502|Color=8388608|FontID=1|IsHidden=T|Text=0.02inch|Name=Width
|RECORD=41|OwnerIndex=826|IndexInSheet=30|OwnerPartId=-1|Location.X=839|Location.Y=502|Color=8388608|FontID=1|IsHidden=T|Text=1005|Name=Case Code (Metric)
|RECORD=41|OwnerIndex=826|IndexInSheet=31|OwnerPartId=-1|Location.X=839|Location.Y=502|Color=8388608|FontID=1|IsHidden=T|Text=10%|Name=Tolerance
|RECORD=34|OwnerIndex=826|IndexInSheet=-1|OwnerPartId=-1|Location.X=840|Location.Y=480|Orientation=1|Color=8388608|FontID=2|Text=C70|Name=Designator|ReadOnlyState=1
|RECORD=41|OwnerIndex=826|IndexInSheet=-1|OwnerPartId=1|Location.X=870|Location.Y=465|Orientation=1|Color=8388608|FontID=2|Text=0.1uF_25V_0402|Name=Comment
|RECORD=44|OwnerIndex=826
|RECORD=45|OwnerIndex=863|IndexInSheet=-1|UseComponentLibrary=T|ModelName=FP-0402-L_1_0_1-W_0_5_0_1-IPC_C|ModelType=PCBLIB|DatafileCount=1|ModelDatafileEntity0=FP-0402-L_1_0_1-W_0_5_0_1-IPC_C|ModelDatafileKind0=PCBLib|IsCurrent=T|DatalinksLocked=T|DatabaseDatalinksLocked=T
|RECORD=46|OwnerIndex=864
|RECORD=48|OwnerIndex=864
|RECORD=45|OwnerIndex=863|IndexInSheet=-1|UseComponentLibrary=T|ModelName=FP-0402-L_1_0_1-W_0_5_0_1-IPC_B|ModelType=PCBLIB|DatafileCount=1|ModelDatafileEntity0=FP-0402-L_1_0_1-W_0_5_0_1-IPC_B|ModelDatafileKind0=PCBLib|DatalinksLocked=T|DatabaseDatalinksLocked=T
|RECORD=46|OwnerIndex=867
|RECORD=48|OwnerIndex=867
|RECORD=45|OwnerIndex=863|IndexInSheet=-1|UseComponentLibrary=T|ModelName=FP-0402-L_1_0_1-W_0_5_0_1-MFG|ModelType=PCBLIB|DatafileCount=1|ModelDatafileEntity0=FP-0402-L_1_0_1-W_0_5_0_1-MFG|ModelDatafileKind0=PCBLib|DatalinksLocked=T|DatabaseDatalinksLocked=T
|RECORD=46|OwnerIndex=870
|RECORD=48|OwnerIndex=870
|RECORD=45|OwnerIndex=863|IndexInSheet=-1|UseComponentLibrary=T|ModelName=FP-0402-L_1_0_1-W_0_5_0_1-IPC_A|ModelType=PCBLIB|DatafileCount=1|ModelDatafileEntity0=FP-0402-L_1_0_1-W_0_5_0_1-IPC_A|ModelDatafileKind0=PCBLib|DatalinksLocked=T|DatabaseDatalinksLocked=T
|RECORD=46|OwnerIndex=873
|RECORD=48|OwnerIndex=873
|RECORD=17|IndexInSheet=84|OwnerPartId=-1|ShowNetName=T|Location.X=850|Location.Y=550|Orientation=1|Color=128|FontID=1|Text=+3.3V
|RECORD=17|IndexInSheet=85|OwnerPartId=-1|Style=4|ShowNetName=T|Location.X=850|Location.Y=470|Orientation=3|Color=128|FontID=1|Text=GND
|RECORD=17|IndexInSheet=86|OwnerPartId=-1|ShowNetName=T|Location.X=750|Location.Y=440|Orientation=2|Color=255|FontID=1|Text=PCIE_PERST|IsCrossSheetConnector=T
|RECORD=1|LibReference=RES|PartCount=2|DisplayModeCount=2|IndexInSheet=87|OwnerPartId=-1|Location.X=790|Location.Y=450|CurrentPartId=1|SourceLibraryName=Altium Content Vault|TargetFileName=*|AreaColor=11599871|Color=128|PartIDLocked=F|DesignItemId=CMP-2002-08434-1|AllPinCount=2
|RECORD=2|OwnerIndex=879|OwnerPartId=1|OwnerPartDisplayMode=1|FormalType=1|Electrical=4|PinConglomerate=32|PinLength=10|Location.X=810|Location.Y=440|Name=2|Designator=2|PinPropagationDelay=0.000000E+000
|RECORD=2|OwnerIndex=879|OwnerPartId=1|OwnerPartDisplayMode=1|FormalType=1|Electrical=4|PinConglomerate=34|PinLength=10|Location.X=790|Location.Y=440|Name=1|Designator=1|PinPropagationDelay=0.000000E+000
|RECORD=14|OwnerIndex=879|IsNotAccesible=T|IndexInSheet=2|OwnerPartId=1|OwnerPartDisplayMode=1|Location.X=790|Location.Y=436|Corner.X=810|Corner.Y=444|LineWidth=1|Color=16711680|AreaColor=11599871
|RECORD=2|OwnerIndex=879|OwnerPartId=1|FormalType=1|Electrical=4|PinConglomerate=32|PinLength=10|Location.X=810|Location.Y=440|Name=2|Designator=2|PinPropagationDelay=0.000000E+000
|RECORD=2|OwnerIndex=879|OwnerPartId=1|FormalType=1|Electrical=4|PinConglomerate=34|PinLength=10|Location.X=790|Location.Y=440|Name=1|Designator=1|PinPropagationDelay=0.000000E+000
|RECORD=6|OwnerIndex=879|IsNotAccesible=T|IndexInSheet=5|OwnerPartId=1|LineWidth=1|Color=16711680|LocationCount=10|X1=810|Y1=440|X2=806|Y2=440|X3=805|Y3=438|X4=803|Y4=442|X5=801|Y5=438|X6=799|Y6=442|X7=797|Y7=438|X8=795|Y8=442|X9=794|Y9=440|X10=790|Y10=440
|RECORD=41|OwnerIndex=879|IndexInSheet=6|OwnerPartId=-1|Location.X=778|Location.Y=453|Color=8388608|FontID=1|IsHidden=T|Text=CRCW040227R0FKED|Name=Part Number
|RECORD=41|OwnerIndex=879|IndexInSheet=7|OwnerPartId=-1|Location.X=778|Location.Y=453|Color=8388608|FontID=1|IsHidden=T|Text=Vishay Dale|Name=Manufacturer
|RECORD=34|OwnerIndex=879|IndexInSheet=-1|OwnerPartId=-1|Location.X=770|Location.Y=440|Color=8388608|FontID=1|Text=R121|Name=Designator|ReadOnlyState=1
|RECORD=41|OwnerIndex=879|IndexInSheet=-1|OwnerPartId=-1|Location.X=790|Location.Y=440|Color=8388608|FontID=1|Text=27_1%_0402|Name=Comment
|RECORD=44|OwnerIndex=879
|RECORD=45|OwnerIndex=894|IndexInSheet=-1|Description=Chip Resistor, 2-Leads, Body 1.00x0.50mm, IPC Medium Density|UseComponentLibrary=T|ModelName=RESC1005X40X25NL05T05|ModelType=PCBLIB|DatafileCount=1|ModelDatafileEntity0=RESC1005X40X25NL05T05|ModelDatafileKind0=PCBLib|IsCurrent=T|DatalinksLocked=T|DatabaseDatalinksLocked=T
|RECORD=46|OwnerIndex=895
|RECORD=48|OwnerIndex=895
|RECORD=41|OwnerIndex=897|IndexInSheet=-1|OwnerPartId=-1|Color=8388608|FontID=1|IsHidden=T|Text=2D|Name=Available Preview Images
|RECORD=45|OwnerIndex=894|IndexInSheet=-1|Description=Chip Resistor, 2-Leads, Body 1.00x0.50mm, IPC High Density|UseComponentLibrary=T|ModelName=RESC1005X40X25LL05T05|ModelType=PCBLIB|DatafileCount=1|ModelDatafileEntity0=RESC1005X40X25LL05T05|ModelDatafileKind0=PCBLib|DatalinksLocked=T|DatabaseDatalinksLocked=T
|RECORD=46|OwnerIndex=899
|RECORD=48|OwnerIndex=899
|RECORD=41|OwnerIndex=901|IndexInSheet=-1|OwnerPartId=-1|Color=8388608|FontID=1|IsHidden=T|Text=2D|Name=Available Preview Images
|RECORD=45|OwnerIndex=894|IndexInSheet=-1|Description=Chip Resistor, 2-Leads, Body 1.00x0.50mm, IPC Low Density|UseComponentLibrary=T|ModelName=RESC1005X40X25ML05T05|ModelType=PCBLIB|DatafileCount=1|ModelDatafileEntity0=RESC1005X40X25ML05T05|ModelDatafileKind0=PCBLib|DatalinksLocked=T|DatabaseDatalinksLocked=T
|RECORD=46|OwnerIndex=903
|RECORD=48|OwnerIndex=903
|RECORD=41|OwnerIndex=905|IndexInSheet=-1|OwnerPartId=-1|Color=8388608|FontID=1|IsHidden=T|Text=2D|Name=Available Preview Images
|RECORD=17|IndexInSheet=88|OwnerPartId=-1|ShowNetName=T|Location.X=640|Location.Y=340|Orientation=2|Color=255|FontID=1|Text=SCL|IsCrossSheetConnector=T
|RECORD=17|IndexInSheet=89|OwnerPartId=-1|ShowNetName=T|Location.X=640|Location.Y=350|Orientation=2|Color=255|FontID=1|Text=SDA|IsCrossSheetConnector=T
|RECORD=17|IndexInSheet=90|OwnerPartId=-1|Style=4|ShowNetName=T|Location.X=1060|Location.Y=310|Orientation=3|Color=128|FontID=1|Text=GND
|RECORD=17|IndexInSheet=91|OwnerPartId=-1|Style=1|ShowNetName=T|Location.X=1320|Location.Y=340|Color=255|FontID=1|Text=MAC_I2C_SCL|IsCrossSheetConnector=T
|RECORD=17|IndexInSheet=92|OwnerPartId=-1|Style=1|ShowNetName=T|Location.X=1320|Location.Y=350|Color=255|FontID=1|Text=MAC_I2C_SDA|IsCrossSheetConnector=T
|RECORD=1|LibReference=RES|PartCount=2|DisplayModeCount=2|IndexInSheet=93|OwnerPartId=-1|Location.X=660|Location.Y=380|Orientation=1|CurrentPartId=1|SourceLibraryName=Altium Content Vault|TargetFileName=*|AreaColor=11599871|Color=128|PartIDLocked=F|DesignItemId=CMP-2002-05217-1|AllPinCount=2
|RECORD=2|OwnerIndex=912|OwnerPartId=1|OwnerPartDisplayMode=1|FormalType=1|Electrical=4|PinConglomerate=33|PinLength=10|Location.X=670|Location.Y=400|Name=2|Designator=2|PinPropagationDelay=0.000000E+000
|RECORD=2|OwnerIndex=912|OwnerPartId=1|OwnerPartDisplayMode=1|FormalType=1|Electrical=4|PinConglomerate=35|PinLength=10|Location.X=670|Location.Y=380|Name=1|Designator=1|PinPropagationDelay=0.000000E+000
|RECORD=14|OwnerIndex=912|IsNotAccesible=T|IndexInSheet=2|OwnerPartId=1|OwnerPartDisplayMode=1|Location.X=666|Location.Y=380|Corner.X=674|Corner.Y=400|LineWidth=1|Color=16711680|AreaColor=11599871
|RECORD=2|OwnerIndex=912|OwnerPartId=1|FormalType=1|Electrical=4|PinConglomerate=33|PinLength=10|Location.X=670|Location.Y=400|Name=2|Designator=2|PinPropagationDelay=0.000000E+000
|RECORD=2|OwnerIndex=912|OwnerPartId=1|FormalType=1|Electrical=4|PinConglomerate=35|PinLength=10|Location.X=670|Location.Y=380|Name=1|Designator=1|PinPropagationDelay=0.000000E+000
|RECORD=6|OwnerIndex=912|IsNotAccesible=T|IndexInSheet=5|OwnerPartId=1|LineWidth=1|Color=16711680|LocationCount=10|X1=670|Y1=400|X2=670|Y2=396|X3=672|Y3=395|X4=668|Y4=393|X5=672|Y5=391|X6=668|Y6=389|X7=672|Y7=387|X8=668|Y8=385|X9=670|Y9=384|X10=670|Y10=380
|RECORD=41|OwnerIndex=912|IndexInSheet=6|OwnerPartId=-1|Location.X=667|Location.Y=412|Color=8388608|FontID=1|IsHidden=T|Text=Bourns|Name=Manufacturer
|RECORD=41|OwnerIndex=912|IndexInSheet=7|OwnerPartId=-1|Location.X=667|Location.Y=412|Color=8388608|FontID=1|IsHidden=T|Text=CR0402-FX-4701GLF|Name=Part Number
|RECORD=34|OwnerIndex=912|IndexInSheet=-1|OwnerPartId=-1|Location.X=670|Location.Y=370|Orientation=1|Color=8388608|FontID=2|Text=R123|Name=Designator|ReadOnlyState=1
|RECORD=41|OwnerIndex=912|IndexInSheet=-1|OwnerPartId=-1|Location.X=680|Location.Y=370|Orientation=1|Color=8388608|FontID=2|Text=4.7K_1%_0402|Name=Comment
|RECORD=44|OwnerIndex=912
|RECORD=45|OwnerIndex=927|IndexInSheet=-1|Description=Chip Resistor, 2-Leads, Body 1.00x0.50mm, IPC Medium Density|UseComponentLibrary=T|ModelName=RESC1005X40X25NL10T10|ModelType=PCBLIB|DatafileCount=1|ModelDatafileEntity0=RESC1005X40X25NL10T10|ModelDatafileKind0=PCBLib|IsCurrent=T|DatalinksLocked=T|DatabaseDatalinksLocked=T
|RECORD=46|OwnerIndex=928
|RECORD=48|OwnerIndex=928
|RECORD=41|OwnerIndex=930|IndexInSheet=-1|OwnerPartId=-1|Color=8388608|FontID=1|IsHidden=T|Text=2D|Name=Available Preview Images
|RECORD=45|OwnerIndex=927|IndexInSheet=-1|Description=Chip Resistor, 2-Leads, Body 1.00x0.50mm, IPC High Density|UseComponentLibrary=T|ModelName=RESC1005X40X25LL10T10|ModelType=PCBLIB|DatafileCount=1|ModelDatafileEntity0=RESC1005X40X25LL10T10|ModelDatafileKind0=PCBLib|DatalinksLocked=T|DatabaseDatalinksLocked=T
|RECORD=46|OwnerIndex=932
|RECORD=48|OwnerIndex=932
|RECORD=41|OwnerIndex=934|IndexInSheet=-1|OwnerPartId=-1|Color=8388608|FontID=1|IsHidden=T|Text=2D|Name=Available Preview Images
|RECORD=45|OwnerIndex=927|IndexInSheet=-1|Description=Chip Resistor, 2-Leads, Body 1.00x0.50mm, IPC Low Density|UseComponentLibrary=T|ModelName=RESC1005X40X25ML10T10|ModelType=PCBLIB|DatafileCount=1|ModelDatafileEntity0=RESC1005X40X25ML10T10|ModelDatafileKind0=PCBLib|DatalinksLocked=T|DatabaseDatalinksLocked=T
|RECORD=46|OwnerIndex=936
|RECORD=48|OwnerIndex=936
|RECORD=41|OwnerIndex=938|IndexInSheet=-1|OwnerPartId=-1|Color=8388608|FontID=1|IsHidden=T|Text=2D|Name=Available Preview Images
|RECORD=1|LibReference=RES|PartCount=2|DisplayModeCount=2|IndexInSheet=94|OwnerPartId=-1|Location.X=680|Location.Y=380|Orientation=1|CurrentPartId=1|SourceLibraryName=Altium Content Vault|TargetFileName=*|AreaColor=11599871|Color=128|PartIDLocked=F|DesignItemId=CMP-2002-05217-1|AllPinCount=2
|RECORD=2|OwnerIndex=940|OwnerPartId=1|OwnerPartDisplayMode=1|FormalType=1|Electrical=4|PinConglomerate=33|PinLength=10|Location.X=690|Location.Y=400|Name=2|Designator=2|PinPropagationDelay=0.000000E+000
|RECORD=2|OwnerIndex=940|OwnerPartId=1|OwnerPartDisplayMode=1|FormalType=1|Electrical=4|PinConglomerate=35|PinLength=10|Location.X=690|Location.Y=380|Name=1|Designator=1|PinPropagationDelay=0.000000E+000
|RECORD=14|OwnerIndex=940|IsNotAccesible=T|IndexInSheet=2|OwnerPartId=1|OwnerPartDisplayMode=1|Location.X=686|Location.Y=380|Corner.X=694|Corner.Y=400|LineWidth=1|Color=16711680|AreaColor=11599871
|RECORD=2|OwnerIndex=940|OwnerPartId=1|FormalType=1|Electrical=4|PinConglomerate=33|PinLength=10|Location.X=690|Location.Y=400|Name=2|Designator=2|PinPropagationDelay=0.000000E+000
|RECORD=2|OwnerIndex=940|OwnerPartId=1|FormalType=1|Electrical=4|PinConglomerate=35|PinLength=10|Location.X=690|Location.Y=380|Name=1|Designator=1|PinPropagationDelay=0.000000E+000
|RECORD=6|OwnerIndex=940|IsNotAccesible=T|IndexInSheet=5|OwnerPartId=1|LineWidth=1|Color=16711680|LocationCount=10|X1=690|Y1=400|X2=690|Y2=396|X3=692|Y3=395|X4=688|Y4=393|X5=692|Y5=391|X6=688|Y6=389|X7=692|Y7=387|X8=688|Y8=385|X9=690|Y9=384|X10=690|Y10=380
|RECORD=41|OwnerIndex=940|IndexInSheet=6|OwnerPartId=-1|Location.X=687|Location.Y=412|Color=8388608|FontID=1|IsHidden=T|Text=Bourns|Name=Manufacturer
|RECORD=41|OwnerIndex=940|IndexInSheet=7|OwnerPartId=-1|Location.X=687|Location.Y=412|Color=8388608|FontID=1|IsHidden=T|Text=CR0402-FX-4701GLF|Name=Part Number
|RECORD=34|OwnerIndex=940|IndexInSheet=-1|OwnerPartId=-1|Location.X=690|Location.Y=370|Orientation=1|Color=8388608|FontID=2|Text=R124|Name=Designator|ReadOnlyState=1
|RECORD=41|OwnerIndex=940|IndexInSheet=-1|OwnerPartId=-1|Location.X=700|Location.Y=370|Orientation=1|Color=8388608|FontID=2|Text=4.7K_1%_0402|Name=Comment
|RECORD=44|OwnerIndex=940
|RECORD=45|OwnerIndex=955|IndexInSheet=-1|Description=Chip Resistor, 2-Leads, Body 1.00x0.50mm, IPC Medium Density|UseComponentLibrary=T|ModelName=RESC1005X40X25NL10T10|ModelType=PCBLIB|DatafileCount=1|ModelDatafileEntity0=RESC1005X40X25NL10T10|ModelDatafileKind0=PCBLib|IsCurrent=T|DatalinksLocked=T|DatabaseDatalinksLocked=T
|RECORD=46|OwnerIndex=956
|RECORD=48|OwnerIndex=956
|RECORD=41|OwnerIndex=958|IndexInSheet=-1|OwnerPartId=-1|Color=8388608|FontID=1|IsHidden=T|Text=2D|Name=Available Preview Images
|RECORD=45|OwnerIndex=955|IndexInSheet=-1|Description=Chip Resistor, 2-Leads, Body 1.00x0.50mm, IPC High Density|UseComponentLibrary=T|ModelName=RESC1005X40X25LL10T10|ModelType=PCBLIB|DatafileCount=1|ModelDatafileEntity0=RESC1005X40X25LL10T10|ModelDatafileKind0=PCBLib|DatalinksLocked=T|DatabaseDatalinksLocked=T
|RECORD=46|OwnerIndex=960
|RECORD=48|OwnerIndex=960
|RECORD=41|OwnerIndex=962|IndexInSheet=-1|OwnerPartId=-1|Color=8388608|FontID=1|IsHidden=T|Text=2D|Name=Available Preview Images
|RECORD=45|OwnerIndex=955|IndexInSheet=-1|Description=Chip Resistor, 2-Leads, Body 1.00x0.50mm, IPC Low Density|UseComponentLibrary=T|ModelName=RESC1005X40X25ML10T10|ModelType=PCBLIB|DatafileCount=1|ModelDatafileEntity0=RESC1005X40X25ML10T10|ModelDatafileKind0=PCBLib|DatalinksLocked=T|DatabaseDatalinksLocked=T
|RECORD=46|OwnerIndex=964
|RECORD=48|OwnerIndex=964
|RECORD=41|OwnerIndex=966|IndexInSheet=-1|OwnerPartId=-1|Color=8388608|FontID=1|IsHidden=T|Text=2D|Name=Available Preview Images
|RECORD=17|IndexInSheet=95|OwnerPartId=-1|ShowNetName=T|Location.X=670|Location.Y=470|Orientation=1|Color=128|FontID=1|Text=+3.3V
|RECORD=1|LibReference=RES|PartCount=2|DisplayModeCount=2|IndexInSheet=96|OwnerPartId=-1|Location.X=1080|Location.Y=490|Orientation=1|CurrentPartId=1|SourceLibraryName=Altium Content Vault|TargetFileName=*|AreaColor=11599871|Color=128|PartIDLocked=F|DesignItemId=CMP-2002-05217-1|AllPinCount=2
|RECORD=2|OwnerIndex=969|OwnerPartId=1|OwnerPartDisplayMode=1|FormalType=1|Electrical=4|PinConglomerate=33|PinLength=10|Location.X=1090|Location.Y=510|Name=2|Designator=2|PinPropagationDelay=0.000000E+000
|RECORD=2|OwnerIndex=969|OwnerPartId=1|OwnerPartDisplayMode=1|FormalType=1|Electrical=4|PinConglomerate=35|PinLength=10|Location.X=1090|Location.Y=490|Name=1|Designator=1|PinPropagationDelay=0.000000E+000
|RECORD=14|OwnerIndex=969|IsNotAccesible=T|IndexInSheet=2|OwnerPartId=1|OwnerPartDisplayMode=1|Location.X=1086|Location.Y=490|Corner.X=1094|Corner.Y=510|LineWidth=1|Color=16711680|AreaColor=11599871
|RECORD=2|OwnerIndex=969|OwnerPartId=1|FormalType=1|Electrical=4|PinConglomerate=33|PinLength=10|Location.X=1090|Location.Y=510|Name=2|Designator=2|PinPropagationDelay=0.000000E+000
|RECORD=2|OwnerIndex=969|OwnerPartId=1|FormalType=1|Electrical=4|PinConglomerate=35|PinLength=10|Location.X=1090|Location.Y=490|Name=1|Designator=1|PinPropagationDelay=0.000000E+000
|RECORD=6|OwnerIndex=969|IsNotAccesible=T|IndexInSheet=5|OwnerPartId=1|LineWidth=1|Color=16711680|LocationCount=10|X1=1090|Y1=510|X2=1090|Y2=506|X3=1092|Y3=505|X4=1088|Y4=503|X5=1092|Y5=501|X6=1088|Y6=499|X7=1092|Y7=497|X8=1088|Y8=495|X9=1090|Y9=494|X10=1090|Y10=490
|RECORD=41|OwnerIndex=969|IndexInSheet=6|OwnerPartId=-1|Location.X=1087|Location.Y=522|Color=8388608|FontID=1|IsHidden=T|Text=Bourns|Name=Manufacturer
|RECORD=41|OwnerIndex=969|IndexInSheet=7|OwnerPartId=-1|Location.X=1087|Location.Y=522|Color=8388608|FontID=1|IsHidden=T|Text=CR0402-FX-4701GLF|Name=Part Number
|RECORD=34|OwnerIndex=969|IndexInSheet=-1|OwnerPartId=-1|Location.X=1090|Location.Y=480|Orientation=1|Color=8388608|FontID=2|Text=R113|Name=Designator|ReadOnlyState=1
|RECORD=41|OwnerIndex=969|IndexInSheet=-1|OwnerPartId=-1|Location.X=1100|Location.Y=480|Orientation=1|Color=8388608|FontID=2|Text=4.7K_1%_0402|Name=Comment
|RECORD=44|OwnerIndex=969
|RECORD=45|OwnerIndex=984|IndexInSheet=-1|Description=Chip Resistor, 2-Leads, Body 1.00x0.50mm, IPC Medium Density|UseComponentLibrary=T|ModelName=RESC1005X40X25NL10T10|ModelType=PCBLIB|DatafileCount=1|ModelDatafileEntity0=RESC1005X40X25NL10T10|ModelDatafileKind0=PCBLib|IsCurrent=T|DatalinksLocked=T|DatabaseDatalinksLocked=T
|RECORD=46|OwnerIndex=985
|RECORD=48|OwnerIndex=985
|RECORD=41|OwnerIndex=987|IndexInSheet=-1|OwnerPartId=-1|Color=8388608|FontID=1|IsHidden=T|Text=2D|Name=Available Preview Images
|RECORD=45|OwnerIndex=984|IndexInSheet=-1|Description=Chip Resistor, 2-Leads, Body 1.00x0.50mm, IPC High Density|UseComponentLibrary=T|ModelName=RESC1005X40X25LL10T10|ModelType=PCBLIB|DatafileCount=1|ModelDatafileEntity0=RESC1005X40X25LL10T10|ModelDatafileKind0=PCBLib|DatalinksLocked=T|DatabaseDatalinksLocked=T
|RECORD=46|OwnerIndex=989
|RECORD=48|OwnerIndex=989
|RECORD=41|OwnerIndex=991|IndexInSheet=-1|OwnerPartId=-1|Color=8388608|FontID=1|IsHidden=T|Text=2D|Name=Available Preview Images
|RECORD=45|OwnerIndex=984|IndexInSheet=-1|Description=Chip Resistor, 2-Leads, Body 1.00x0.50mm, IPC Low Density|UseComponentLibrary=T|ModelName=RESC1005X40X25ML10T10|ModelType=PCBLIB|DatafileCount=1|ModelDatafileEntity0=RESC1005X40X25ML10T10|ModelDatafileKind0=PCBLib|DatalinksLocked=T|DatabaseDatalinksLocked=T
|RECORD=46|OwnerIndex=993
|RECORD=48|OwnerIndex=993
|RECORD=41|OwnerIndex=995|IndexInSheet=-1|OwnerPartId=-1|Color=8388608|FontID=1|IsHidden=T|Text=2D|Name=Available Preview Images
|RECORD=1|LibReference=RES|PartCount=2|DisplayModeCount=2|IndexInSheet=97|OwnerPartId=-1|Location.X=1100|Location.Y=490|Orientation=1|CurrentPartId=1|SourceLibraryName=Altium Content Vault|TargetFileName=*|AreaColor=11599871|Color=128|PartIDLocked=F|DesignItemId=CMP-2002-05217-1|AllPinCount=2
|RECORD=2|OwnerIndex=997|OwnerPartId=1|OwnerPartDisplayMode=1|FormalType=1|Electrical=4|PinConglomerate=33|PinLength=10|Location.X=1110|Location.Y=510|Name=2|Designator=2|PinPropagationDelay=0.000000E+000
|RECORD=2|OwnerIndex=997|OwnerPartId=1|OwnerPartDisplayMode=1|FormalType=1|Electrical=4|PinConglomerate=35|PinLength=10|Location.X=1110|Location.Y=490|Name=1|Designator=1|PinPropagationDelay=0.000000E+000
|RECORD=14|OwnerIndex=997|IsNotAccesible=T|IndexInSheet=2|OwnerPartId=1|OwnerPartDisplayMode=1|Location.X=1106|Location.Y=490|Corner.X=1114|Corner.Y=510|LineWidth=1|Color=16711680|AreaColor=11599871
|RECORD=2|OwnerIndex=997|OwnerPartId=1|FormalType=1|Electrical=4|PinConglomerate=33|PinLength=10|Location.X=1110|Location.Y=510|Name=2|Designator=2|PinPropagationDelay=0.000000E+000
|RECORD=2|OwnerIndex=997|OwnerPartId=1|FormalType=1|Electrical=4|PinConglomerate=35|PinLength=10|Location.X=1110|Location.Y=490|Name=1|Designator=1|PinPropagationDelay=0.000000E+000
|RECORD=6|OwnerIndex=997|IsNotAccesible=T|IndexInSheet=5|OwnerPartId=1|LineWidth=1|Color=16711680|LocationCount=10|X1=1110|Y1=510|X2=1110|Y2=506|X3=1112|Y3=505|X4=1108|Y4=503|X5=1112|Y5=501|X6=1108|Y6=499|X7=1112|Y7=497|X8=1108|Y8=495|X9=1110|Y9=494|X10=1110|Y10=490
|RECORD=41|OwnerIndex=997|IndexInSheet=6|OwnerPartId=-1|Location.X=1107|Location.Y=522|Color=8388608|FontID=1|IsHidden=T|Text=Bourns|Name=Manufacturer
|RECORD=41|OwnerIndex=997|IndexInSheet=7|OwnerPartId=-1|Location.X=1107|Location.Y=522|Color=8388608|FontID=1|IsHidden=T|Text=CR0402-FX-4701GLF|Name=Part Number
|RECORD=34|OwnerIndex=997|IndexInSheet=-1|OwnerPartId=-1|Location.X=1110|Location.Y=480|Orientation=1|Color=8388608|FontID=2|Text=R114|Name=Designator|ReadOnlyState=1
|RECORD=41|OwnerIndex=997|IndexInSheet=-1|OwnerPartId=-1|Location.X=1120|Location.Y=480|Orientation=1|Color=8388608|FontID=2|Text=4.7K_1%_0402|Name=Comment
|RECORD=44|OwnerIndex=997
|RECORD=45|OwnerIndex=1012|IndexInSheet=-1|Description=Chip Resistor, 2-Leads, Body 1.00x0.50mm, IPC Medium Density|UseComponentLibrary=T|ModelName=RESC1005X40X25NL10T10|ModelType=PCBLIB|DatafileCount=1|ModelDatafileEntity0=RESC1005X40X25NL10T10|ModelDatafileKind0=PCBLib|IsCurrent=T|DatalinksLocked=T|DatabaseDatalinksLocked=T
|RECORD=46|OwnerIndex=1013
|RECORD=48|OwnerIndex=1013
|RECORD=41|OwnerIndex=1015|IndexInSheet=-1|OwnerPartId=-1|Color=8388608|FontID=1|IsHidden=T|Text=2D|Name=Available Preview Images
|RECORD=45|OwnerIndex=1012|IndexInSheet=-1|Description=Chip Resistor, 2-Leads, Body 1.00x0.50mm, IPC High Density|UseComponentLibrary=T|ModelName=RESC1005X40X25LL10T10|ModelType=PCBLIB|DatafileCount=1|ModelDatafileEntity0=RESC1005X40X25LL10T10|ModelDatafileKind0=PCBLib|DatalinksLocked=T|DatabaseDatalinksLocked=T
|RECORD=46|OwnerIndex=1017
|RECORD=48|OwnerIndex=1017
|RECORD=41|OwnerIndex=1019|IndexInSheet=-1|OwnerPartId=-1|Color=8388608|FontID=1|IsHidden=T|Text=2D|Name=Available Preview Images
|RECORD=45|OwnerIndex=1012|IndexInSheet=-1|Description=Chip Resistor, 2-Leads, Body 1.00x0.50mm, IPC Low Density|UseComponentLibrary=T|ModelName=RESC1005X40X25ML10T10|ModelType=PCBLIB|DatafileCount=1|ModelDatafileEntity0=RESC1005X40X25ML10T10|ModelDatafileKind0=PCBLib|DatalinksLocked=T|DatabaseDatalinksLocked=T
|RECORD=46|OwnerIndex=1021
|RECORD=48|OwnerIndex=1021
|RECORD=41|OwnerIndex=1023|IndexInSheet=-1|OwnerPartId=-1|Color=8388608|FontID=1|IsHidden=T|Text=2D|Name=Available Preview Images
|RECORD=1|LibReference=RES|PartCount=2|DisplayModeCount=2|IndexInSheet=98|OwnerPartId=-1|Location.X=1130|Location.Y=490|Orientation=1|CurrentPartId=1|SourceLibraryName=Altium Content Vault|TargetFileName=*|AreaColor=11599871|Color=128|PartIDLocked=F|DesignItemId=CMP-2002-05217-1|AllPinCount=2
|RECORD=2|OwnerIndex=1025|OwnerPartId=1|OwnerPartDisplayMode=1|FormalType=1|Electrical=4|PinConglomerate=33|PinLength=10|Location.X=1140|Location.Y=510|Name=2|Designator=2|PinPropagationDelay=0.000000E+000
|RECORD=2|OwnerIndex=1025|OwnerPartId=1|OwnerPartDisplayMode=1|FormalType=1|Electrical=4|PinConglomerate=35|PinLength=10|Location.X=1140|Location.Y=490|Name=1|Designator=1|PinPropagationDelay=0.000000E+000
|RECORD=14|OwnerIndex=1025|IsNotAccesible=T|IndexInSheet=2|OwnerPartId=1|OwnerPartDisplayMode=1|Location.X=1136|Location.Y=490|Corner.X=1144|Corner.Y=510|LineWidth=1|Color=16711680|AreaColor=11599871
|RECORD=2|OwnerIndex=1025|OwnerPartId=1|FormalType=1|Electrical=4|PinConglomerate=33|PinLength=10|Location.X=1140|Location.Y=510|Name=2|Designator=2|PinPropagationDelay=0.000000E+000
|RECORD=2|OwnerIndex=1025|OwnerPartId=1|FormalType=1|Electrical=4|PinConglomerate=35|PinLength=10|Location.X=1140|Location.Y=490|Name=1|Designator=1|PinPropagationDelay=0.000000E+000
|RECORD=6|OwnerIndex=1025|IsNotAccesible=T|IndexInSheet=5|OwnerPartId=1|LineWidth=1|Color=16711680|LocationCount=10|X1=1140|Y1=510|X2=1140|Y2=506|X3=1142|Y3=505|X4=1138|Y4=503|X5=1142|Y5=501|X6=1138|Y6=499|X7=1142|Y7=497|X8=1138|Y8=495|X9=1140|Y9=494|X10=1140|Y10=490
|RECORD=41|OwnerIndex=1025|IndexInSheet=6|OwnerPartId=-1|Location.X=1137|Location.Y=522|Color=8388608|FontID=1|IsHidden=T|Text=Bourns|Name=Manufacturer
|RECORD=41|OwnerIndex=1025|IndexInSheet=7|OwnerPartId=-1|Location.X=1137|Location.Y=522|Color=8388608|FontID=1|IsHidden=T|Text=CR0402-FX-4701GLF|Name=Part Number
|RECORD=34|OwnerIndex=1025|IndexInSheet=-1|OwnerPartId=-1|Location.X=1140|Location.Y=480|Orientation=1|Color=8388608|FontID=2|Text=R115|Name=Designator|ReadOnlyState=1
|RECORD=41|OwnerIndex=1025|IndexInSheet=-1|OwnerPartId=-1|Location.X=1150|Location.Y=480|Orientation=1|Color=8388608|FontID=2|Text=4.7K_1%_0402|Name=Comment
|RECORD=44|OwnerIndex=1025
|RECORD=45|OwnerIndex=1040|IndexInSheet=-1|Description=Chip Resistor, 2-Leads, Body 1.00x0.50mm, IPC Medium Density|UseComponentLibrary=T|ModelName=RESC1005X40X25NL10T10|ModelType=PCBLIB|DatafileCount=1|ModelDatafileEntity0=RESC1005X40X25NL10T10|ModelDatafileKind0=PCBLib|IsCurrent=T|DatalinksLocked=T|DatabaseDatalinksLocked=T
|RECORD=46|OwnerIndex=1041
|RECORD=48|OwnerIndex=1041
|RECORD=41|OwnerIndex=1043|IndexInSheet=-1|OwnerPartId=-1|Color=8388608|FontID=1|IsHidden=T|Text=2D|Name=Available Preview Images
|RECORD=45|OwnerIndex=1040|IndexInSheet=-1|Description=Chip Resistor, 2-Leads, Body 1.00x0.50mm, IPC High Density|UseComponentLibrary=T|ModelName=RESC1005X40X25LL10T10|ModelType=PCBLIB|DatafileCount=1|ModelDatafileEntity0=RESC1005X40X25LL10T10|ModelDatafileKind0=PCBLib|DatalinksLocked=T|DatabaseDatalinksLocked=T
|RECORD=46|OwnerIndex=1045
|RECORD=48|OwnerIndex=1045
|RECORD=41|OwnerIndex=1047|IndexInSheet=-1|OwnerPartId=-1|Color=8388608|FontID=1|IsHidden=T|Text=2D|Name=Available Preview Images
|RECORD=45|OwnerIndex=1040|IndexInSheet=-1|Description=Chip Resistor, 2-Leads, Body 1.00x0.50mm, IPC Low Density|UseComponentLibrary=T|ModelName=RESC1005X40X25ML10T10|ModelType=PCBLIB|DatafileCount=1|ModelDatafileEntity0=RESC1005X40X25ML10T10|ModelDatafileKind0=PCBLib|DatalinksLocked=T|DatabaseDatalinksLocked=T
|RECORD=46|OwnerIndex=1049
|RECORD=48|OwnerIndex=1049
|RECORD=41|OwnerIndex=1051|IndexInSheet=-1|OwnerPartId=-1|Color=8388608|FontID=1|IsHidden=T|Text=2D|Name=Available Preview Images
|RECORD=1|LibReference=RES|PartCount=2|DisplayModeCount=2|IndexInSheet=99|OwnerPartId=-1|Location.X=1150|Location.Y=490|Orientation=1|CurrentPartId=1|SourceLibraryName=Altium Content Vault|TargetFileName=*|AreaColor=11599871|Color=128|PartIDLocked=F|DesignItemId=CMP-2002-05217-1|AllPinCount=2
|RECORD=2|OwnerIndex=1053|OwnerPartId=1|OwnerPartDisplayMode=1|FormalType=1|Electrical=4|PinConglomerate=33|PinLength=10|Location.X=1160|Location.Y=510|Name=2|Designator=2|PinPropagationDelay=0.000000E+000
|RECORD=2|OwnerIndex=1053|OwnerPartId=1|OwnerPartDisplayMode=1|FormalType=1|Electrical=4|PinConglomerate=35|PinLength=10|Location.X=1160|Location.Y=490|Name=1|Designator=1|PinPropagationDelay=0.000000E+000
|RECORD=14|OwnerIndex=1053|IsNotAccesible=T|IndexInSheet=2|OwnerPartId=1|OwnerPartDisplayMode=1|Location.X=1156|Location.Y=490|Corner.X=1164|Corner.Y=510|LineWidth=1|Color=16711680|AreaColor=11599871
|RECORD=2|OwnerIndex=1053|OwnerPartId=1|FormalType=1|Electrical=4|PinConglomerate=33|PinLength=10|Location.X=1160|Location.Y=510|Name=2|Designator=2|PinPropagationDelay=0.000000E+000
|RECORD=2|OwnerIndex=1053|OwnerPartId=1|FormalType=1|Electrical=4|PinConglomerate=35|PinLength=10|Location.X=1160|Location.Y=490|Name=1|Designator=1|PinPropagationDelay=0.000000E+000
|RECORD=6|OwnerIndex=1053|IsNotAccesible=T|IndexInSheet=5|OwnerPartId=1|LineWidth=1|Color=16711680|LocationCount=10|X1=1160|Y1=510|X2=1160|Y2=506|X3=1162|Y3=505|X4=1158|Y4=503|X5=1162|Y5=501|X6=1158|Y6=499|X7=1162|Y7=497|X8=1158|Y8=495|X9=1160|Y9=494|X10=1160|Y10=490
|RECORD=41|OwnerIndex=1053|IndexInSheet=6|OwnerPartId=-1|Location.X=1157|Location.Y=522|Color=8388608|FontID=1|IsHidden=T|Text=Bourns|Name=Manufacturer
|RECORD=41|OwnerIndex=1053|IndexInSheet=7|OwnerPartId=-1|Location.X=1157|Location.Y=522|Color=8388608|FontID=1|IsHidden=T|Text=CR0402-FX-4701GLF|Name=Part Number
|RECORD=34|OwnerIndex=1053|IndexInSheet=-1|OwnerPartId=-1|Location.X=1160|Location.Y=480|Orientation=1|Color=8388608|FontID=2|Text=R116|Name=Designator|ReadOnlyState=1
|RECORD=41|OwnerIndex=1053|IndexInSheet=-1|OwnerPartId=-1|Location.X=1170|Location.Y=480|Orientation=1|Color=8388608|FontID=2|Text=4.7K_1%_0402|Name=Comment
|RECORD=44|OwnerIndex=1053
|RECORD=45|OwnerIndex=1068|IndexInSheet=-1|Description=Chip Resistor, 2-Leads, Body 1.00x0.50mm, IPC Medium Density|UseComponentLibrary=T|ModelName=RESC1005X40X25NL10T10|ModelType=PCBLIB|DatafileCount=1|ModelDatafileEntity0=RESC1005X40X25NL10T10|ModelDatafileKind0=PCBLib|IsCurrent=T|DatalinksLocked=T|DatabaseDatalinksLocked=T
|RECORD=46|OwnerIndex=1069
|RECORD=48|OwnerIndex=1069
|RECORD=41|OwnerIndex=1071|IndexInSheet=-1|OwnerPartId=-1|Color=8388608|FontID=1|IsHidden=T|Text=2D|Name=Available Preview Images
|RECORD=45|OwnerIndex=1068|IndexInSheet=-1|Description=Chip Resistor, 2-Leads, Body 1.00x0.50mm, IPC High Density|UseComponentLibrary=T|ModelName=RESC1005X40X25LL10T10|ModelType=PCBLIB|DatafileCount=1|ModelDatafileEntity0=RESC1005X40X25LL10T10|ModelDatafileKind0=PCBLib|DatalinksLocked=T|DatabaseDatalinksLocked=T
|RECORD=46|OwnerIndex=1073
|RECORD=48|OwnerIndex=1073
|RECORD=41|OwnerIndex=1075|IndexInSheet=-1|OwnerPartId=-1|Color=8388608|FontID=1|IsHidden=T|Text=2D|Name=Available Preview Images
|RECORD=45|OwnerIndex=1068|IndexInSheet=-1|Description=Chip Resistor, 2-Leads, Body 1.00x0.50mm, IPC Low Density|UseComponentLibrary=T|ModelName=RESC1005X40X25ML10T10|ModelType=PCBLIB|DatafileCount=1|ModelDatafileEntity0=RESC1005X40X25ML10T10|ModelDatafileKind0=PCBLib|DatalinksLocked=T|DatabaseDatalinksLocked=T
|RECORD=46|OwnerIndex=1077
|RECORD=48|OwnerIndex=1077
|RECORD=41|OwnerIndex=1079|IndexInSheet=-1|OwnerPartId=-1|Color=8388608|FontID=1|IsHidden=T|Text=2D|Name=Available Preview Images
|RECORD=1|LibReference=RES|PartCount=2|DisplayModeCount=2|IndexInSheet=100|OwnerPartId=-1|Location.X=1180|Location.Y=490|Orientation=1|CurrentPartId=1|SourceLibraryName=Altium Content Vault|TargetFileName=*|AreaColor=11599871|Color=128|PartIDLocked=F|DesignItemId=CMP-2002-05217-1|AllPinCount=2
|RECORD=2|OwnerIndex=1081|OwnerPartId=1|OwnerPartDisplayMode=1|FormalType=1|Electrical=4|PinConglomerate=33|PinLength=10|Location.X=1190|Location.Y=510|Name=2|Designator=2|PinPropagationDelay=0.000000E+000
|RECORD=2|OwnerIndex=1081|OwnerPartId=1|OwnerPartDisplayMode=1|FormalType=1|Electrical=4|PinConglomerate=35|PinLength=10|Location.X=1190|Location.Y=490|Name=1|Designator=1|PinPropagationDelay=0.000000E+000
|RECORD=14|OwnerIndex=1081|IsNotAccesible=T|IndexInSheet=2|OwnerPartId=1|OwnerPartDisplayMode=1|Location.X=1186|Location.Y=490|Corner.X=1194|Corner.Y=510|LineWidth=1|Color=16711680|AreaColor=11599871
|RECORD=2|OwnerIndex=1081|OwnerPartId=1|FormalType=1|Electrical=4|PinConglomerate=33|PinLength=10|Location.X=1190|Location.Y=510|Name=2|Designator=2|PinPropagationDelay=0.000000E+000
|RECORD=2|OwnerIndex=1081|OwnerPartId=1|FormalType=1|Electrical=4|PinConglomerate=35|PinLength=10|Location.X=1190|Location.Y=490|Name=1|Designator=1|PinPropagationDelay=0.000000E+000
|RECORD=6|OwnerIndex=1081|IsNotAccesible=T|IndexInSheet=5|OwnerPartId=1|LineWidth=1|Color=16711680|LocationCount=10|X1=1190|Y1=510|X2=1190|Y2=506|X3=1192|Y3=505|X4=1188|Y4=503|X5=1192|Y5=501|X6=1188|Y6=499|X7=1192|Y7=497|X8=1188|Y8=495|X9=1190|Y9=494|X10=1190|Y10=490
|RECORD=41|OwnerIndex=1081|IndexInSheet=6|OwnerPartId=-1|Location.X=1187|Location.Y=522|Color=8388608|FontID=1|IsHidden=T|Text=Bourns|Name=Manufacturer
|RECORD=41|OwnerIndex=1081|IndexInSheet=7|OwnerPartId=-1|Location.X=1187|Location.Y=522|Color=8388608|FontID=1|IsHidden=T|Text=CR0402-FX-4701GLF|Name=Part Number
|RECORD=34|OwnerIndex=1081|IndexInSheet=-1|OwnerPartId=-1|Location.X=1190|Location.Y=480|Orientation=1|Color=8388608|FontID=2|Text=R117|Name=Designator|ReadOnlyState=1
|RECORD=41|OwnerIndex=1081|IndexInSheet=-1|OwnerPartId=-1|Location.X=1200|Location.Y=480|Orientation=1|Color=8388608|FontID=2|Text=4.7K_1%_0402|Name=Comment
|RECORD=44|OwnerIndex=1081
|RECORD=45|OwnerIndex=1096|IndexInSheet=-1|Description=Chip Resistor, 2-Leads, Body 1.00x0.50mm, IPC Medium Density|UseComponentLibrary=T|ModelName=RESC1005X40X25NL10T10|ModelType=PCBLIB|DatafileCount=1|ModelDatafileEntity0=RESC1005X40X25NL10T10|ModelDatafileKind0=PCBLib|IsCurrent=T|DatalinksLocked=T|DatabaseDatalinksLocked=T
|RECORD=46|OwnerIndex=1097
|RECORD=48|OwnerIndex=1097
|RECORD=41|OwnerIndex=1099|IndexInSheet=-1|OwnerPartId=-1|Color=8388608|FontID=1|IsHidden=T|Text=2D|Name=Available Preview Images
|RECORD=45|OwnerIndex=1096|IndexInSheet=-1|Description=Chip Resistor, 2-Leads, Body 1.00x0.50mm, IPC High Density|UseComponentLibrary=T|ModelName=RESC1005X40X25LL10T10|ModelType=PCBLIB|DatafileCount=1|ModelDatafileEntity0=RESC1005X40X25LL10T10|ModelDatafileKind0=PCBLib|DatalinksLocked=T|DatabaseDatalinksLocked=T
|RECORD=46|OwnerIndex=1101
|RECORD=48|OwnerIndex=1101
|RECORD=41|OwnerIndex=1103|IndexInSheet=-1|OwnerPartId=-1|Color=8388608|FontID=1|IsHidden=T|Text=2D|Name=Available Preview Images
|RECORD=45|OwnerIndex=1096|IndexInSheet=-1|Description=Chip Resistor, 2-Leads, Body 1.00x0.50mm, IPC Low Density|UseComponentLibrary=T|ModelName=RESC1005X40X25ML10T10|ModelType=PCBLIB|DatafileCount=1|ModelDatafileEntity0=RESC1005X40X25ML10T10|ModelDatafileKind0=PCBLib|DatalinksLocked=T|DatabaseDatalinksLocked=T
|RECORD=46|OwnerIndex=1105
|RECORD=48|OwnerIndex=1105
|RECORD=41|OwnerIndex=1107|IndexInSheet=-1|OwnerPartId=-1|Color=8388608|FontID=1|IsHidden=T|Text=2D|Name=Available Preview Images
|RECORD=1|LibReference=RES|PartCount=2|DisplayModeCount=2|IndexInSheet=101|OwnerPartId=-1|Location.X=1200|Location.Y=490|Orientation=1|CurrentPartId=1|SourceLibraryName=Altium Content Vault|TargetFileName=*|AreaColor=11599871|Color=128|PartIDLocked=F|DesignItemId=CMP-2002-05217-1|AllPinCount=2
|RECORD=2|OwnerIndex=1109|OwnerPartId=1|OwnerPartDisplayMode=1|FormalType=1|Electrical=4|PinConglomerate=33|PinLength=10|Location.X=1210|Location.Y=510|Name=2|Designator=2|PinPropagationDelay=0.000000E+000
|RECORD=2|OwnerIndex=1109|OwnerPartId=1|OwnerPartDisplayMode=1|FormalType=1|Electrical=4|PinConglomerate=35|PinLength=10|Location.X=1210|Location.Y=490|Name=1|Designator=1|PinPropagationDelay=0.000000E+000
|RECORD=14|OwnerIndex=1109|IsNotAccesible=T|IndexInSheet=2|OwnerPartId=1|OwnerPartDisplayMode=1|Location.X=1206|Location.Y=490|Corner.X=1214|Corner.Y=510|LineWidth=1|Color=16711680|AreaColor=11599871
|RECORD=2|OwnerIndex=1109|OwnerPartId=1|FormalType=1|Electrical=4|PinConglomerate=33|PinLength=10|Location.X=1210|Location.Y=510|Name=2|Designator=2|PinPropagationDelay=0.000000E+000
|RECORD=2|OwnerIndex=1109|OwnerPartId=1|FormalType=1|Electrical=4|PinConglomerate=35|PinLength=10|Location.X=1210|Location.Y=490|Name=1|Designator=1|PinPropagationDelay=0.000000E+000
|RECORD=6|OwnerIndex=1109|IsNotAccesible=T|IndexInSheet=5|OwnerPartId=1|LineWidth=1|Color=16711680|LocationCount=10|X1=1210|Y1=510|X2=1210|Y2=506|X3=1212|Y3=505|X4=1208|Y4=503|X5=1212|Y5=501|X6=1208|Y6=499|X7=1212|Y7=497|X8=1208|Y8=495|X9=1210|Y9=494|X10=1210|Y10=490
|RECORD=41|OwnerIndex=1109|IndexInSheet=6|OwnerPartId=-1|Location.X=1207|Location.Y=522|Color=8388608|FontID=1|IsHidden=T|Text=Bourns|Name=Manufacturer
|RECORD=41|OwnerIndex=1109|IndexInSheet=7|OwnerPartId=-1|Location.X=1207|Location.Y=522|Color=8388608|FontID=1|IsHidden=T|Text=CR0402-FX-4701GLF|Name=Part Number
|RECORD=34|OwnerIndex=1109|IndexInSheet=-1|OwnerPartId=-1|Location.X=1210|Location.Y=480|Orientation=1|Color=8388608|FontID=2|Text=R118|Name=Designator|ReadOnlyState=1
|RECORD=41|OwnerIndex=1109|IndexInSheet=-1|OwnerPartId=-1|Location.X=1220|Location.Y=480|Orientation=1|Color=8388608|FontID=2|Text=4.7K_1%_0402|Name=Comment
|RECORD=44|OwnerIndex=1109
|RECORD=45|OwnerIndex=1124|IndexInSheet=-1|Description=Chip Resistor, 2-Leads, Body 1.00x0.50mm, IPC Medium Density|UseComponentLibrary=T|ModelName=RESC1005X40X25NL10T10|ModelType=PCBLIB|DatafileCount=1|ModelDatafileEntity0=RESC1005X40X25NL10T10|ModelDatafileKind0=PCBLib|IsCurrent=T|DatalinksLocked=T|DatabaseDatalinksLocked=T
|RECORD=46|OwnerIndex=1125
|RECORD=48|OwnerIndex=1125
|RECORD=41|OwnerIndex=1127|IndexInSheet=-1|OwnerPartId=-1|Color=8388608|FontID=1|IsHidden=T|Text=2D|Name=Available Preview Images
|RECORD=45|OwnerIndex=1124|IndexInSheet=-1|Description=Chip Resistor, 2-Leads, Body 1.00x0.50mm, IPC High Density|UseComponentLibrary=T|ModelName=RESC1005X40X25LL10T10|ModelType=PCBLIB|DatafileCount=1|ModelDatafileEntity0=RESC1005X40X25LL10T10|ModelDatafileKind0=PCBLib|DatalinksLocked=T|DatabaseDatalinksLocked=T
|RECORD=46|OwnerIndex=1129
|RECORD=48|OwnerIndex=1129
|RECORD=41|OwnerIndex=1131|IndexInSheet=-1|OwnerPartId=-1|Color=8388608|FontID=1|IsHidden=T|Text=2D|Name=Available Preview Images
|RECORD=45|OwnerIndex=1124|IndexInSheet=-1|Description=Chip Resistor, 2-Leads, Body 1.00x0.50mm, IPC Low Density|UseComponentLibrary=T|ModelName=RESC1005X40X25ML10T10|ModelType=PCBLIB|DatafileCount=1|ModelDatafileEntity0=RESC1005X40X25ML10T10|ModelDatafileKind0=PCBLib|DatalinksLocked=T|DatabaseDatalinksLocked=T
|RECORD=46|OwnerIndex=1133
|RECORD=48|OwnerIndex=1133
|RECORD=41|OwnerIndex=1135|IndexInSheet=-1|OwnerPartId=-1|Color=8388608|FontID=1|IsHidden=T|Text=2D|Name=Available Preview Images
|RECORD=1|LibReference=RES|PartCount=2|DisplayModeCount=2|IndexInSheet=102|OwnerPartId=-1|Location.X=1230|Location.Y=490|Orientation=1|CurrentPartId=1|SourceLibraryName=Altium Content Vault|TargetFileName=*|AreaColor=11599871|Color=128|PartIDLocked=F|DesignItemId=CMP-2002-05217-1|AllPinCount=2
|RECORD=2|OwnerIndex=1137|OwnerPartId=1|OwnerPartDisplayMode=1|FormalType=1|Electrical=4|PinConglomerate=33|PinLength=10|Location.X=1240|Location.Y=510|Name=2|Designator=2|PinPropagationDelay=0.000000E+000
|RECORD=2|OwnerIndex=1137|OwnerPartId=1|OwnerPartDisplayMode=1|FormalType=1|Electrical=4|PinConglomerate=35|PinLength=10|Location.X=1240|Location.Y=490|Name=1|Designator=1|PinPropagationDelay=0.000000E+000
|RECORD=14|OwnerIndex=1137|IsNotAccesible=T|IndexInSheet=2|OwnerPartId=1|OwnerPartDisplayMode=1|Location.X=1236|Location.Y=490|Corner.X=1244|Corner.Y=510|LineWidth=1|Color=16711680|AreaColor=11599871
|RECORD=2|OwnerIndex=1137|OwnerPartId=1|FormalType=1|Electrical=4|PinConglomerate=33|PinLength=10|Location.X=1240|Location.Y=510|Name=2|Designator=2|PinPropagationDelay=0.000000E+000
|RECORD=2|OwnerIndex=1137|OwnerPartId=1|FormalType=1|Electrical=4|PinConglomerate=35|PinLength=10|Location.X=1240|Location.Y=490|Name=1|Designator=1|PinPropagationDelay=0.000000E+000
|RECORD=6|OwnerIndex=1137|IsNotAccesible=T|IndexInSheet=5|OwnerPartId=1|LineWidth=1|Color=16711680|LocationCount=10|X1=1240|Y1=510|X2=1240|Y2=506|X3=1242|Y3=505|X4=1238|Y4=503|X5=1242|Y5=501|X6=1238|Y6=499|X7=1242|Y7=497|X8=1238|Y8=495|X9=1240|Y9=494|X10=1240|Y10=490
|RECORD=41|OwnerIndex=1137|IndexInSheet=6|OwnerPartId=-1|Location.X=1237|Location.Y=522|Color=8388608|FontID=1|IsHidden=T|Text=Bourns|Name=Manufacturer
|RECORD=41|OwnerIndex=1137|IndexInSheet=7|OwnerPartId=-1|Location.X=1237|Location.Y=522|Color=8388608|FontID=1|IsHidden=T|Text=CR0402-FX-4701GLF|Name=Part Number
|RECORD=34|OwnerIndex=1137|IndexInSheet=-1|OwnerPartId=-1|Location.X=1240|Location.Y=480|Orientation=1|Color=8388608|FontID=2|Text=R119|Name=Designator|ReadOnlyState=1
|RECORD=41|OwnerIndex=1137|IndexInSheet=-1|OwnerPartId=-1|Location.X=1250|Location.Y=480|Orientation=1|Color=8388608|FontID=2|Text=4.7K_1%_0402|Name=Comment
|RECORD=44|OwnerIndex=1137
|RECORD=45|OwnerIndex=1152|IndexInSheet=-1|Description=Chip Resistor, 2-Leads, Body 1.00x0.50mm, IPC Medium Density|UseComponentLibrary=T|ModelName=RESC1005X40X25NL10T10|ModelType=PCBLIB|DatafileCount=1|ModelDatafileEntity0=RESC1005X40X25NL10T10|ModelDatafileKind0=PCBLib|IsCurrent=T|DatalinksLocked=T|DatabaseDatalinksLocked=T
|RECORD=46|OwnerIndex=1153
|RECORD=48|OwnerIndex=1153
|RECORD=41|OwnerIndex=1155|IndexInSheet=-1|OwnerPartId=-1|Color=8388608|FontID=1|IsHidden=T|Text=2D|Name=Available Preview Images
|RECORD=45|OwnerIndex=1152|IndexInSheet=-1|Description=Chip Resistor, 2-Leads, Body 1.00x0.50mm, IPC High Density|UseComponentLibrary=T|ModelName=RESC1005X40X25LL10T10|ModelType=PCBLIB|DatafileCount=1|ModelDatafileEntity0=RESC1005X40X25LL10T10|ModelDatafileKind0=PCBLib|DatalinksLocked=T|DatabaseDatalinksLocked=T
|RECORD=46|OwnerIndex=1157
|RECORD=48|OwnerIndex=1157
|RECORD=41|OwnerIndex=1159|IndexInSheet=-1|OwnerPartId=-1|Color=8388608|FontID=1|IsHidden=T|Text=2D|Name=Available Preview Images
|RECORD=45|OwnerIndex=1152|IndexInSheet=-1|Description=Chip Resistor, 2-Leads, Body 1.00x0.50mm, IPC Low Density|UseComponentLibrary=T|ModelName=RESC1005X40X25ML10T10|ModelType=PCBLIB|DatafileCount=1|ModelDatafileEntity0=RESC1005X40X25ML10T10|ModelDatafileKind0=PCBLib|DatalinksLocked=T|DatabaseDatalinksLocked=T
|RECORD=46|OwnerIndex=1161
|RECORD=48|OwnerIndex=1161
|RECORD=41|OwnerIndex=1163|IndexInSheet=-1|OwnerPartId=-1|Color=8388608|FontID=1|IsHidden=T|Text=2D|Name=Available Preview Images
|RECORD=1|LibReference=RES|PartCount=2|DisplayModeCount=2|IndexInSheet=103|OwnerPartId=-1|Location.X=1250|Location.Y=490|Orientation=1|CurrentPartId=1|SourceLibraryName=Altium Content Vault|TargetFileName=*|AreaColor=11599871|Color=128|PartIDLocked=F|DesignItemId=CMP-2002-05217-1|AllPinCount=2
|RECORD=2|OwnerIndex=1165|OwnerPartId=1|OwnerPartDisplayMode=1|FormalType=1|Electrical=4|PinConglomerate=33|PinLength=10|Location.X=1260|Location.Y=510|Name=2|Designator=2|PinPropagationDelay=0.000000E+000
|RECORD=2|OwnerIndex=1165|OwnerPartId=1|OwnerPartDisplayMode=1|FormalType=1|Electrical=4|PinConglomerate=35|PinLength=10|Location.X=1260|Location.Y=490|Name=1|Designator=1|PinPropagationDelay=0.000000E+000
|RECORD=14|OwnerIndex=1165|IsNotAccesible=T|IndexInSheet=2|OwnerPartId=1|OwnerPartDisplayMode=1|Location.X=1256|Location.Y=490|Corner.X=1264|Corner.Y=510|LineWidth=1|Color=16711680|AreaColor=11599871
|RECORD=2|OwnerIndex=1165|OwnerPartId=1|FormalType=1|Electrical=4|PinConglomerate=33|PinLength=10|Location.X=1260|Location.Y=510|Name=2|Designator=2|PinPropagationDelay=0.000000E+000
|RECORD=2|OwnerIndex=1165|OwnerPartId=1|FormalType=1|Electrical=4|PinConglomerate=35|PinLength=10|Location.X=1260|Location.Y=490|Name=1|Designator=1|PinPropagationDelay=0.000000E+000
|RECORD=6|OwnerIndex=1165|IsNotAccesible=T|IndexInSheet=5|OwnerPartId=1|LineWidth=1|Color=16711680|LocationCount=10|X1=1260|Y1=510|X2=1260|Y2=506|X3=1262|Y3=505|X4=1258|Y4=503|X5=1262|Y5=501|X6=1258|Y6=499|X7=1262|Y7=497|X8=1258|Y8=495|X9=1260|Y9=494|X10=1260|Y10=490
|RECORD=41|OwnerIndex=1165|IndexInSheet=6|OwnerPartId=-1|Location.X=1257|Location.Y=522|Color=8388608|FontID=1|IsHidden=T|Text=Bourns|Name=Manufacturer
|RECORD=41|OwnerIndex=1165|IndexInSheet=7|OwnerPartId=-1|Location.X=1257|Location.Y=522|Color=8388608|FontID=1|IsHidden=T|Text=CR0402-FX-4701GLF|Name=Part Number
|RECORD=34|OwnerIndex=1165|IndexInSheet=-1|OwnerPartId=-1|Location.X=1260|Location.Y=480|Orientation=1|Color=8388608|FontID=2|Text=R120|Name=Designator|ReadOnlyState=1
|RECORD=41|OwnerIndex=1165|IndexInSheet=-1|OwnerPartId=-1|Location.X=1270|Location.Y=480|Orientation=1|Color=8388608|FontID=2|Text=4.7K_1%_0402|Name=Comment
|RECORD=44|OwnerIndex=1165
|RECORD=45|OwnerIndex=1180|IndexInSheet=-1|Description=Chip Resistor, 2-Leads, Body 1.00x0.50mm, IPC Medium Density|UseComponentLibrary=T|ModelName=RESC1005X40X25NL10T10|ModelType=PCBLIB|DatafileCount=1|ModelDatafileEntity0=RESC1005X40X25NL10T10|ModelDatafileKind0=PCBLib|IsCurrent=T|DatalinksLocked=T|DatabaseDatalinksLocked=T
|RECORD=46|OwnerIndex=1181
|RECORD=48|OwnerIndex=1181
|RECORD=41|OwnerIndex=1183|IndexInSheet=-1|OwnerPartId=-1|Color=8388608|FontID=1|IsHidden=T|Text=2D|Name=Available Preview Images
|RECORD=45|OwnerIndex=1180|IndexInSheet=-1|Description=Chip Resistor, 2-Leads, Body 1.00x0.50mm, IPC High Density|UseComponentLibrary=T|ModelName=RESC1005X40X25LL10T10|ModelType=PCBLIB|DatafileCount=1|ModelDatafileEntity0=RESC1005X40X25LL10T10|ModelDatafileKind0=PCBLib|DatalinksLocked=T|DatabaseDatalinksLocked=T
|RECORD=46|OwnerIndex=1185
|RECORD=48|OwnerIndex=1185
|RECORD=41|OwnerIndex=1187|IndexInSheet=-1|OwnerPartId=-1|Color=8388608|FontID=1|IsHidden=T|Text=2D|Name=Available Preview Images
|RECORD=45|OwnerIndex=1180|IndexInSheet=-1|Description=Chip Resistor, 2-Leads, Body 1.00x0.50mm, IPC Low Density|UseComponentLibrary=T|ModelName=RESC1005X40X25ML10T10|ModelType=PCBLIB|DatafileCount=1|ModelDatafileEntity0=RESC1005X40X25ML10T10|ModelDatafileKind0=PCBLib|DatalinksLocked=T|DatabaseDatalinksLocked=T
|RECORD=46|OwnerIndex=1189
|RECORD=48|OwnerIndex=1189
|RECORD=41|OwnerIndex=1191|IndexInSheet=-1|OwnerPartId=-1|Color=8388608|FontID=1|IsHidden=T|Text=2D|Name=Available Preview Images
|RECORD=17|IndexInSheet=104|OwnerPartId=-1|ShowNetName=T|Location.X=1090|Location.Y=560|Orientation=1|Color=128|FontID=1|Text=+3.3V
|RECORD=17|IndexInSheet=105|OwnerPartId=-1|Style=1|ShowNetName=T|Location.X=1320|Location.Y=400|Color=255|FontID=1|Text=ANADC_I2C_SCL|IsCrossSheetConnector=T
|RECORD=17|IndexInSheet=106|OwnerPartId=-1|Style=1|ShowNetName=T|Location.X=1320|Location.Y=410|Color=255|FontID=1|Text=ANADC_I2C_SDA|IsCrossSheetConnector=T
|RECORD=17|IndexInSheet=107|OwnerPartId=-1|Style=1|ShowNetName=T|Location.X=1320|Location.Y=430|Color=255|FontID=1|Text=DC_I2C_SCL|IsCrossSheetConnector=T
|RECORD=17|IndexInSheet=108|OwnerPartId=-1|Style=1|ShowNetName=T|Location.X=1320|Location.Y=440|Color=255|FontID=1|Text=DC_I2C_SDA|IsCrossSheetConnector=T
|RECORD=17|IndexInSheet=109|OwnerPartId=-1|Style=1|ShowNetName=T|Location.X=1320|Location.Y=370|Color=255|FontID=1|Text=SENS_I2C_SCL|IsCrossSheetConnector=T
|RECORD=17|IndexInSheet=110|OwnerPartId=-1|Style=1|ShowNetName=T|Location.X=1320|Location.Y=380|Color=255|FontID=1|Text=SENS_I2C_SDA|IsCrossSheetConnector=T
|RECORD=1|LibReference=6123b3bffd52fd60b6df23d79e332fa|ComponentDescription=SWITCH SLIDE DIP SPST 25MA 24V|PartCount=5|DisplayModeCount=1|IndexInSheet=111|OwnerPartId=-1|Location.X=220|Location.Y=730|CurrentPartId=1|LibraryPath=*|SourceLibraryName=Altium Content Vault|TargetFileName=*|AreaColor=11599871|Color=128|PartIDLocked=T|DesignItemId=CMP-03400-000014-1|AllPinCount=8
|RECORD=2|OwnerIndex=1200|OwnerPartId=1|Electrical=4|PinConglomerate=50|PinLength=20|Location.X=240|Location.Y=730|Name=1|Designator=1|PinPropagationDelay=0.000000E+000
|RECORD=2|OwnerIndex=1200|OwnerPartId=1|Electrical=4|PinConglomerate=48|PinLength=20|Location.X=260|Location.Y=730|Name=8|Designator=8|PinPropagationDelay=0.000000E+000
|RECORD=8|OwnerIndex=1200|IsNotAccesible=T|IndexInSheet=2|OwnerPartId=1|Location.X=243|Location.Y=730|Radius=2|SecondaryRadius=2|LineWidth=1|Color=16711680
|RECORD=8|OwnerIndex=1200|IsNotAccesible=T|IndexInSheet=3|OwnerPartId=1|Location.X=257|Location.Y=730|Radius=2|SecondaryRadius=2|LineWidth=1|Color=16711680
|RECORD=13|OwnerIndex=1200|IsNotAccesible=T|IndexInSheet=4|OwnerPartId=1|Location.X=245|Location.Y=731|Corner.X=255|Corner.Y=737|LineWidth=1|Color=16711680
|RECORD=13|OwnerIndex=1200|IsNotAccesible=T|IndexInSheet=5|OwnerPartId=1|Location.X=240|Location.Y=730|Corner.X=237|Corner.Y=730|LineWidth=1|Color=16711680
|RECORD=13|OwnerIndex=1200|IsNotAccesible=T|IndexInSheet=6|OwnerPartId=1|Location.X=260|Location.Y=730|Corner.X=263|Corner.Y=730|LineWidth=1|Color=16711680
|RECORD=8|OwnerIndex=1200|IsNotAccesible=T|IndexInSheet=7|OwnerPartId=2|Location.X=243|Location.Y=730|Radius=2|SecondaryRadius=2|LineWidth=1|Color=16711680
|RECORD=8|OwnerIndex=1200|IsNotAccesible=T|IndexInSheet=8|OwnerPartId=2|Location.X=257|Location.Y=730|Radius=2|SecondaryRadius=2|LineWidth=1|Color=16711680
|RECORD=13|OwnerIndex=1200|IsNotAccesible=T|IndexInSheet=9|OwnerPartId=2|Location.X=245|Location.Y=731|Corner.X=255|Corner.Y=737|LineWidth=1|Color=16711680
|RECORD=2|OwnerIndex=1200|OwnerPartId=2|Electrical=4|PinConglomerate=50|PinLength=20|Location.X=240|Location.Y=730|Name=2|Designator=2|PinPropagationDelay=0.000000E+000
|RECORD=2|OwnerIndex=1200|OwnerPartId=2|Electrical=4|PinConglomerate=48|PinLength=20|Location.X=260|Location.Y=730|Name=7|Designator=7|PinPropagationDelay=0.000000E+000
|RECORD=8|OwnerIndex=1200|IsNotAccesible=T|IndexInSheet=12|OwnerPartId=3|Location.X=243|Location.Y=730|Radius=2|SecondaryRadius=2|LineWidth=1|Color=16711680
|RECORD=8|OwnerIndex=1200|IsNotAccesible=T|IndexInSheet=13|OwnerPartId=3|Location.X=257|Location.Y=730|Radius=2|SecondaryRadius=2|LineWidth=1|Color=16711680
|RECORD=13|OwnerIndex=1200|IsNotAccesible=T|IndexInSheet=14|OwnerPartId=3|Location.X=245|Location.Y=731|Corner.X=255|Corner.Y=737|LineWidth=1|Color=16711680
|RECORD=2|OwnerIndex=1200|OwnerPartId=3|Electrical=4|PinConglomerate=50|PinLength=20|Location.X=240|Location.Y=730|Name=3|Designator=3|PinPropagationDelay=0.000000E+000
|RECORD=2|OwnerIndex=1200|OwnerPartId=3|Electrical=4|PinConglomerate=48|PinLength=20|Location.X=260|Location.Y=730|Name=6|Designator=6|PinPropagationDelay=0.000000E+000
|RECORD=8|OwnerIndex=1200|IsNotAccesible=T|IndexInSheet=17|OwnerPartId=4|Location.X=243|Location.Y=730|Radius=2|SecondaryRadius=2|LineWidth=1|Color=16711680
|RECORD=8|OwnerIndex=1200|IsNotAccesible=T|IndexInSheet=18|OwnerPartId=4|Location.X=257|Location.Y=730|Radius=2|SecondaryRadius=2|LineWidth=1|Color=16711680
|RECORD=13|OwnerIndex=1200|IsNotAccesible=T|IndexInSheet=19|OwnerPartId=4|Location.X=245|Location.Y=731|Corner.X=255|Corner.Y=737|LineWidth=1|Color=16711680
|RECORD=2|OwnerIndex=1200|OwnerPartId=4|Electrical=4|PinConglomerate=50|PinLength=20|Location.X=240|Location.Y=730|Name=4|Designator=4|PinPropagationDelay=0.000000E+000
|RECORD=2|OwnerIndex=1200|OwnerPartId=4|Electrical=4|PinConglomerate=48|PinLength=20|Location.X=260|Location.Y=730|Name=5|Designator=5|PinPropagationDelay=0.000000E+000
|RECORD=41|OwnerIndex=1200|IndexInSheet=22|OwnerPartId=-1|Location.X=218|Location.Y=738|Color=8388608|FontID=3|IsHidden=T|Text=https://www.te.com/commerce/DocumentDelivery/DDEController?Action=showdoc&DocId=Customer+Drawing%7F1571983%7FC6%7Fpdf%7FEnglish%7FENG_CD_1571983_C6.pdf%7F1571983-4|Name=ComponentLink2URL
|RECORD=41|OwnerIndex=1200|IndexInSheet=23|OwnerPartId=-1|Location.X=218|Location.Y=738|Color=8388608|FontID=1|IsHidden=T|Text=SPST|Name=Throw Configuration
|RECORD=41|OwnerIndex=1200|IndexInSheet=24|OwnerPartId=-1|Location.X=218|Location.Y=738|Color=8388608|FontID=1|IsHidden=T|Text=Electromechanical|Name=Device Class L1
|RECORD=41|OwnerIndex=1200|IndexInSheet=25|OwnerPartId=-1|Location.X=218|Location.Y=738|Color=8388608|FontID=1|IsHidden=T|Text=0.1mm|Name=Standoff Height
|RECORD=41|OwnerIndex=1200|IndexInSheet=26|OwnerPartId=-1|Location.X=218|Location.Y=738|Color=8388608|FontID=1|IsHidden=T|Text=Yes|Name=Lead Free
|RECORD=41|OwnerIndex=1200|IndexInSheet=27|OwnerPartId=-1|Location.X=218|Location.Y=738|Color=8388608|FontID=1|IsHidden=T|Text=-30°C|Name=Temperature Range Low
|RECORD=41|OwnerIndex=1200|IndexInSheet=28|OwnerPartId=-1|Location.X=218|Location.Y=738|Color=8388608|FontID=1|IsHidden=T|Text=-30°C to +85°C|Name=Temperature
|RECORD=41|OwnerIndex=1200|IndexInSheet=29|OwnerPartId=-1|Location.X=218|Location.Y=738|Color=8388608|FontID=1|IsHidden=T|Text=1000Cycles|Name=Electromechanical Life
|RECORD=41|OwnerIndex=1200|IndexInSheet=30|OwnerPartId=-1|Location.X=218|Location.Y=738|Color=8388608|FontID=3|IsHidden=T|Text=https://octopart.com/1571983-4-te+connectivity-46507521|Name=Octopart
|RECORD=41|OwnerIndex=1200|IndexInSheet=31|OwnerPartId=-1|Location.X=218|Location.Y=738|Color=8388608|FontID=1|IsHidden=T|Text=TE Connectivity|Name=Manufacturer
|RECORD=41|OwnerIndex=1200|IndexInSheet=32|OwnerPartId=-1|Location.X=218|Location.Y=738|Color=8388608|FontID=1|IsHidden=T|Text=+85°C|Name=Temperature Range High
|RECORD=41|OwnerIndex=1200|IndexInSheet=33|OwnerPartId=-1|Location.X=218|Location.Y=738|Color=8388608|FontID=1|IsHidden=T|Text=1571983-4|Name=Package
|RECORD=41|OwnerIndex=1200|IndexInSheet=34|OwnerPartId=-1|Location.X=218|Location.Y=738|Color=8388608|FontID=1|IsHidden=T|Text=4|Name=Number Of Circuits
|RECORD=41|OwnerIndex=1200|IndexInSheet=35|OwnerPartId=-1|Location.X=218|Location.Y=738|Color=8388608|FontID=1|IsHidden=T|Text=2.56mm|Name=Height
|RECORD=41|OwnerIndex=1200|IndexInSheet=36|OwnerPartId=-1|Location.X=218|Location.Y=738|Color=8388608|FontID=1|IsHidden=T|Text=1571983-4|Name=Manufacturer Part Number
|RECORD=41|OwnerIndex=1200|IndexInSheet=37|OwnerPartId=-1|Location.X=218|Location.Y=738|Color=8388608|FontID=1|IsHidden=T|Text=25mA|Name=Contact Current Rating
|RECORD=41|OwnerIndex=1200|IndexInSheet=38|OwnerPartId=-1|Location.X=218|Location.Y=738|Color=8388608|FontID=1|IsHidden=T|Text=Datasheet|Name=ComponentLink2Description
|RECORD=41|OwnerIndex=1200|IndexInSheet=39|OwnerPartId=-1|Location.X=218|Location.Y=738|Color=8388608|FontID=1|IsHidden=T|Text=DIP Switches|Name=Device Class L3
|RECORD=41|OwnerIndex=1200|IndexInSheet=40|OwnerPartId=-1|Location.X=218|Location.Y=738|Color=8388608|FontID=1|IsHidden=T|Text=Switch|Name=Category
|RECORD=41|OwnerIndex=1200|IndexInSheet=41|OwnerPartId=-1|Location.X=218|Location.Y=738|Color=8388608|FontID=1|IsHidden=T|Text=100mO|Name=Contact Resistance
|RECORD=41|OwnerIndex=1200|IndexInSheet=42|OwnerPartId=-1|Location.X=218|Location.Y=738|Color=8388608|FontID=1|IsHidden=T|Text=Switches|Name=Device Class L2
|RECORD=41|OwnerIndex=1200|IndexInSheet=43|OwnerPartId=-1|Location.X=218|Location.Y=738|Color=8388608|FontID=1|IsHidden=T|Text=TRUE|Name=RoHS
|RECORD=41|OwnerIndex=1200|IndexInSheet=44|OwnerPartId=-1|Location.X=218|Location.Y=738|Color=8388608|FontID=1|IsHidden=T|Text=24V|Name=Voltage Rating Dc
|RECORD=41|OwnerIndex=1200|IndexInSheet=45|OwnerPartId=-1|Location.X=218|Location.Y=738|Color=8388608|FontID=1|IsHidden=T|Text=SWITCH SLIDE DIP SPST 25MA 24V|Name=Digikey Description
|RECORD=41|OwnerIndex=1200|IndexInSheet=46|OwnerPartId=-1|Location.X=218|Location.Y=738|Color=8388608|FontID=1|IsHidden=T|Text=No|Name=Automotive
|RECORD=34|OwnerIndex=1200|IndexInSheet=-1|OwnerPartId=-1|Location.X=236|Location.Y=738|Color=8388608|FontID=1|Text=SW1|Name=Designator|ReadOnlyState=1
|RECORD=41|OwnerIndex=1200|IndexInSheet=-1|OwnerPartId=1|Location.X=236|Location.Y=717|Color=8388608|FontID=1|Text=1571983-4|Name=Comment
|RECORD=44|OwnerIndex=1200
|RECORD=45|OwnerIndex=1258|IndexInSheet=-1|UseComponentLibrary=T|ModelName=FP-1571983-4-MFG|ModelType=PCBLIB|DatafileCount=1|ModelDatafileEntity0=FP-1571983-4-MFG|ModelDatafileKind0=PCBLib|IsCurrent=T|DatalinksLocked=T|DatabaseDatalinksLocked=T
|RECORD=46|OwnerIndex=1259
|RECORD=48|OwnerIndex=1259
|RECORD=1|LibReference=6123b3bffd52fd60b6df23d79e332fa|ComponentDescription=SWITCH SLIDE DIP SPST 25MA 24V|PartCount=5|DisplayModeCount=1|IndexInSheet=112|OwnerPartId=-1|Location.X=220|Location.Y=690|CurrentPartId=2|LibraryPath=*|SourceLibraryName=Altium Content Vault|TargetFileName=*|AreaColor=11599871|Color=128|PartIDLocked=T|DesignItemId=CMP-03400-000014-1|AllPinCount=8
|RECORD=2|OwnerIndex=1262|OwnerPartId=1|Electrical=4|PinConglomerate=50|PinLength=20|Location.X=240|Location.Y=690|Name=1|Designator=1|PinPropagationDelay=0.000000E+000
|RECORD=2|OwnerIndex=1262|OwnerPartId=1|Electrical=4|PinConglomerate=48|PinLength=20|Location.X=260|Location.Y=690|Name=8|Designator=8|PinPropagationDelay=0.000000E+000
|RECORD=8|OwnerIndex=1262|IsNotAccesible=T|IndexInSheet=2|OwnerPartId=1|Location.X=243|Location.Y=690|Radius=2|SecondaryRadius=2|LineWidth=1|Color=16711680
|RECORD=8|OwnerIndex=1262|IsNotAccesible=T|IndexInSheet=3|OwnerPartId=1|Location.X=257|Location.Y=690|Radius=2|SecondaryRadius=2|LineWidth=1|Color=16711680
|RECORD=13|OwnerIndex=1262|IsNotAccesible=T|IndexInSheet=4|OwnerPartId=1|Location.X=245|Location.Y=691|Corner.X=255|Corner.Y=697|LineWidth=1|Color=16711680
|RECORD=13|OwnerIndex=1262|IsNotAccesible=T|IndexInSheet=5|OwnerPartId=1|Location.X=240|Location.Y=690|Corner.X=237|Corner.Y=690|LineWidth=1|Color=16711680
|RECORD=13|OwnerIndex=1262|IsNotAccesible=T|IndexInSheet=6|OwnerPartId=1|Location.X=260|Location.Y=690|Corner.X=263|Corner.Y=690|LineWidth=1|Color=16711680
|RECORD=8|OwnerIndex=1262|IsNotAccesible=T|IndexInSheet=7|OwnerPartId=2|Location.X=243|Location.Y=690|Radius=2|SecondaryRadius=2|LineWidth=1|Color=16711680
|RECORD=8|OwnerIndex=1262|IsNotAccesible=T|IndexInSheet=8|OwnerPartId=2|Location.X=257|Location.Y=690|Radius=2|SecondaryRadius=2|LineWidth=1|Color=16711680
|RECORD=13|OwnerIndex=1262|IsNotAccesible=T|IndexInSheet=9|OwnerPartId=2|Location.X=245|Location.Y=691|Corner.X=255|Corner.Y=697|LineWidth=1|Color=16711680
|RECORD=2|OwnerIndex=1262|OwnerPartId=2|Electrical=4|PinConglomerate=50|PinLength=20|Location.X=240|Location.Y=690|Name=2|Designator=2|PinPropagationDelay=0.000000E+000
|RECORD=2|OwnerIndex=1262|OwnerPartId=2|Electrical=4|PinConglomerate=48|PinLength=20|Location.X=260|Location.Y=690|Name=7|Designator=7|PinPropagationDelay=0.000000E+000
|RECORD=8|OwnerIndex=1262|IsNotAccesible=T|IndexInSheet=12|OwnerPartId=3|Location.X=243|Location.Y=690|Radius=2|SecondaryRadius=2|LineWidth=1|Color=16711680
|RECORD=8|OwnerIndex=1262|IsNotAccesible=T|IndexInSheet=13|OwnerPartId=3|Location.X=257|Location.Y=690|Radius=2|SecondaryRadius=2|LineWidth=1|Color=16711680
|RECORD=13|OwnerIndex=1262|IsNotAccesible=T|IndexInSheet=14|OwnerPartId=3|Location.X=245|Location.Y=691|Corner.X=255|Corner.Y=697|LineWidth=1|Color=16711680
|RECORD=2|OwnerIndex=1262|OwnerPartId=3|Electrical=4|PinConglomerate=50|PinLength=20|Location.X=240|Location.Y=690|Name=3|Designator=3|PinPropagationDelay=0.000000E+000
|RECORD=2|OwnerIndex=1262|OwnerPartId=3|Electrical=4|PinConglomerate=48|PinLength=20|Location.X=260|Location.Y=690|Name=6|Designator=6|PinPropagationDelay=0.000000E+000
|RECORD=8|OwnerIndex=1262|IsNotAccesible=T|IndexInSheet=17|OwnerPartId=4|Location.X=243|Location.Y=690|Radius=2|SecondaryRadius=2|LineWidth=1|Color=16711680
|RECORD=8|OwnerIndex=1262|IsNotAccesible=T|IndexInSheet=18|OwnerPartId=4|Location.X=257|Location.Y=690|Radius=2|SecondaryRadius=2|LineWidth=1|Color=16711680
|RECORD=13|OwnerIndex=1262|IsNotAccesible=T|IndexInSheet=19|OwnerPartId=4|Location.X=245|Location.Y=691|Corner.X=255|Corner.Y=697|LineWidth=1|Color=16711680
|RECORD=2|OwnerIndex=1262|OwnerPartId=4|Electrical=4|PinConglomerate=50|PinLength=20|Location.X=240|Location.Y=690|Name=4|Designator=4|PinPropagationDelay=0.000000E+000
|RECORD=2|OwnerIndex=1262|OwnerPartId=4|Electrical=4|PinConglomerate=48|PinLength=20|Location.X=260|Location.Y=690|Name=5|Designator=5|PinPropagationDelay=0.000000E+000
|RECORD=41|OwnerIndex=1262|IndexInSheet=22|OwnerPartId=-1|Location.X=218|Location.Y=698|Color=8388608|FontID=3|IsHidden=T|Text=https://www.te.com/commerce/DocumentDelivery/DDEController?Action=showdoc&DocId=Customer+Drawing%7F1571983%7FC6%7Fpdf%7FEnglish%7FENG_CD_1571983_C6.pdf%7F1571983-4|Name=ComponentLink2URL
|RECORD=41|OwnerIndex=1262|IndexInSheet=23|OwnerPartId=-1|Location.X=218|Location.Y=698|Color=8388608|FontID=1|IsHidden=T|Text=SPST|Name=Throw Configuration
|RECORD=41|OwnerIndex=1262|IndexInSheet=24|OwnerPartId=-1|Location.X=218|Location.Y=698|Color=8388608|FontID=1|IsHidden=T|Text=Electromechanical|Name=Device Class L1
|RECORD=41|OwnerIndex=1262|IndexInSheet=25|OwnerPartId=-1|Location.X=218|Location.Y=698|Color=8388608|FontID=1|IsHidden=T|Text=0.1mm|Name=Standoff Height
|RECORD=41|OwnerIndex=1262|IndexInSheet=26|OwnerPartId=-1|Location.X=218|Location.Y=698|Color=8388608|FontID=1|IsHidden=T|Text=Yes|Name=Lead Free
|RECORD=41|OwnerIndex=1262|IndexInSheet=27|OwnerPartId=-1|Location.X=218|Location.Y=698|Color=8388608|FontID=1|IsHidden=T|Text=-30°C|Name=Temperature Range Low
|RECORD=41|OwnerIndex=1262|IndexInSheet=28|OwnerPartId=-1|Location.X=218|Location.Y=698|Color=8388608|FontID=1|IsHidden=T|Text=-30°C to +85°C|Name=Temperature
|RECORD=41|OwnerIndex=1262|IndexInSheet=29|OwnerPartId=-1|Location.X=218|Location.Y=698|Color=8388608|FontID=1|IsHidden=T|Text=1000Cycles|Name=Electromechanical Life
|RECORD=41|OwnerIndex=1262|IndexInSheet=30|OwnerPartId=-1|Location.X=218|Location.Y=698|Color=8388608|FontID=3|IsHidden=T|Text=https://octopart.com/1571983-4-te+connectivity-46507521|Name=Octopart
|RECORD=41|OwnerIndex=1262|IndexInSheet=31|OwnerPartId=-1|Location.X=218|Location.Y=698|Color=8388608|FontID=1|IsHidden=T|Text=TE Connectivity|Name=Manufacturer
|RECORD=41|OwnerIndex=1262|IndexInSheet=32|OwnerPartId=-1|Location.X=218|Location.Y=698|Color=8388608|FontID=1|IsHidden=T|Text=+85°C|Name=Temperature Range High
|RECORD=41|OwnerIndex=1262|IndexInSheet=33|OwnerPartId=-1|Location.X=218|Location.Y=698|Color=8388608|FontID=1|IsHidden=T|Text=1571983-4|Name=Package
|RECORD=41|OwnerIndex=1262|IndexInSheet=34|OwnerPartId=-1|Location.X=218|Location.Y=698|Color=8388608|FontID=1|IsHidden=T|Text=4|Name=Number Of Circuits
|RECORD=41|OwnerIndex=1262|IndexInSheet=35|OwnerPartId=-1|Location.X=218|Location.Y=698|Color=8388608|FontID=1|IsHidden=T|Text=2.56mm|Name=Height
|RECORD=41|OwnerIndex=1262|IndexInSheet=36|OwnerPartId=-1|Location.X=218|Location.Y=698|Color=8388608|FontID=1|IsHidden=T|Text=1571983-4|Name=Manufacturer Part Number
|RECORD=41|OwnerIndex=1262|IndexInSheet=37|OwnerPartId=-1|Location.X=218|Location.Y=698|Color=8388608|FontID=1|IsHidden=T|Text=25mA|Name=Contact Current Rating
|RECORD=41|OwnerIndex=1262|IndexInSheet=38|OwnerPartId=-1|Location.X=218|Location.Y=698|Color=8388608|FontID=1|IsHidden=T|Text=Datasheet|Name=ComponentLink2Description
|RECORD=41|OwnerIndex=1262|IndexInSheet=39|OwnerPartId=-1|Location.X=218|Location.Y=698|Color=8388608|FontID=1|IsHidden=T|Text=DIP Switches|Name=Device Class L3
|RECORD=41|OwnerIndex=1262|IndexInSheet=40|OwnerPartId=-1|Location.X=218|Location.Y=698|Color=8388608|FontID=1|IsHidden=T|Text=Switch|Name=Category
|RECORD=41|OwnerIndex=1262|IndexInSheet=41|OwnerPartId=-1|Location.X=218|Location.Y=698|Color=8388608|FontID=1|IsHidden=T|Text=100mO|Name=Contact Resistance
|RECORD=41|OwnerIndex=1262|IndexInSheet=42|OwnerPartId=-1|Location.X=218|Location.Y=698|Color=8388608|FontID=1|IsHidden=T|Text=Switches|Name=Device Class L2
|RECORD=41|OwnerIndex=1262|IndexInSheet=43|OwnerPartId=-1|Location.X=218|Location.Y=698|Color=8388608|FontID=1|IsHidden=T|Text=TRUE|Name=RoHS
|RECORD=41|OwnerIndex=1262|IndexInSheet=44|OwnerPartId=-1|Location.X=218|Location.Y=698|Color=8388608|FontID=1|IsHidden=T|Text=24V|Name=Voltage Rating Dc
|RECORD=41|OwnerIndex=1262|IndexInSheet=45|OwnerPartId=-1|Location.X=218|Location.Y=698|Color=8388608|FontID=1|IsHidden=T|Text=SWITCH SLIDE DIP SPST 25MA 24V|Name=Digikey Description
|RECORD=41|OwnerIndex=1262|IndexInSheet=46|OwnerPartId=-1|Location.X=218|Location.Y=698|Color=8388608|FontID=1|IsHidden=T|Text=No|Name=Automotive
|RECORD=34|OwnerIndex=1262|IndexInSheet=-1|OwnerPartId=-1|Location.X=241|Location.Y=698|Color=8388608|FontID=1|Text=SW1|Name=Designator|ReadOnlyState=1
|RECORD=41|OwnerIndex=1262|IndexInSheet=-1|OwnerPartId=1|Location.X=241|Location.Y=677|Color=8388608|FontID=1|Text=1571983-4|Name=Comment
|RECORD=44|OwnerIndex=1262
|RECORD=45|OwnerIndex=1320|IndexInSheet=-1|UseComponentLibrary=T|ModelName=FP-1571983-4-MFG|ModelType=PCBLIB|DatafileCount=1|ModelDatafileEntity0=FP-1571983-4-MFG|ModelDatafileKind0=PCBLib|IsCurrent=T|DatalinksLocked=T|DatabaseDatalinksLocked=T
|RECORD=46|OwnerIndex=1321
|RECORD=48|OwnerIndex=1321
|RECORD=1|LibReference=6123b3bffd52fd60b6df23d79e332fa|ComponentDescription=SWITCH SLIDE DIP SPST 25MA 24V|PartCount=5|DisplayModeCount=1|IndexInSheet=113|OwnerPartId=-1|Location.X=220|Location.Y=650|CurrentPartId=3|LibraryPath=*|SourceLibraryName=Altium Content Vault|TargetFileName=*|AreaColor=11599871|Color=128|PartIDLocked=T|DesignItemId=CMP-03400-000014-1|AllPinCount=8
|RECORD=2|OwnerIndex=1324|OwnerPartId=1|Electrical=4|PinConglomerate=50|PinLength=20|Location.X=240|Location.Y=650|Name=1|Designator=1|PinPropagationDelay=0.000000E+000
|RECORD=2|OwnerIndex=1324|OwnerPartId=1|Electrical=4|PinConglomerate=48|PinLength=20|Location.X=260|Location.Y=650|Name=8|Designator=8|PinPropagationDelay=0.000000E+000
|RECORD=8|OwnerIndex=1324|IsNotAccesible=T|IndexInSheet=2|OwnerPartId=1|Location.X=243|Location.Y=650|Radius=2|SecondaryRadius=2|LineWidth=1|Color=16711680
|RECORD=8|OwnerIndex=1324|IsNotAccesible=T|IndexInSheet=3|OwnerPartId=1|Location.X=257|Location.Y=650|Radius=2|SecondaryRadius=2|LineWidth=1|Color=16711680
|RECORD=13|OwnerIndex=1324|IsNotAccesible=T|IndexInSheet=4|OwnerPartId=1|Location.X=245|Location.Y=651|Corner.X=255|Corner.Y=657|LineWidth=1|Color=16711680
|RECORD=13|OwnerIndex=1324|IsNotAccesible=T|IndexInSheet=5|OwnerPartId=1|Location.X=240|Location.Y=650|Corner.X=237|Corner.Y=650|LineWidth=1|Color=16711680
|RECORD=13|OwnerIndex=1324|IsNotAccesible=T|IndexInSheet=6|OwnerPartId=1|Location.X=260|Location.Y=650|Corner.X=263|Corner.Y=650|LineWidth=1|Color=16711680
|RECORD=8|OwnerIndex=1324|IsNotAccesible=T|IndexInSheet=7|OwnerPartId=2|Location.X=243|Location.Y=650|Radius=2|SecondaryRadius=2|LineWidth=1|Color=16711680
|RECORD=8|OwnerIndex=1324|IsNotAccesible=T|IndexInSheet=8|OwnerPartId=2|Location.X=257|Location.Y=650|Radius=2|SecondaryRadius=2|LineWidth=1|Color=16711680
|RECORD=13|OwnerIndex=1324|IsNotAccesible=T|IndexInSheet=9|OwnerPartId=2|Location.X=245|Location.Y=651|Corner.X=255|Corner.Y=657|LineWidth=1|Color=16711680
|RECORD=2|OwnerIndex=1324|OwnerPartId=2|Electrical=4|PinConglomerate=50|PinLength=20|Location.X=240|Location.Y=650|Name=2|Designator=2|PinPropagationDelay=0.000000E+000
|RECORD=2|OwnerIndex=1324|OwnerPartId=2|Electrical=4|PinConglomerate=48|PinLength=20|Location.X=260|Location.Y=650|Name=7|Designator=7|PinPropagationDelay=0.000000E+000
|RECORD=8|OwnerIndex=1324|IsNotAccesible=T|IndexInSheet=12|OwnerPartId=3|Location.X=243|Location.Y=650|Radius=2|SecondaryRadius=2|LineWidth=1|Color=16711680
|RECORD=8|OwnerIndex=1324|IsNotAccesible=T|IndexInSheet=13|OwnerPartId=3|Location.X=257|Location.Y=650|Radius=2|SecondaryRadius=2|LineWidth=1|Color=16711680
|RECORD=13|OwnerIndex=1324|IsNotAccesible=T|IndexInSheet=14|OwnerPartId=3|Location.X=245|Location.Y=651|Corner.X=255|Corner.Y=657|LineWidth=1|Color=16711680
|RECORD=2|OwnerIndex=1324|OwnerPartId=3|Electrical=4|PinConglomerate=50|PinLength=20|Location.X=240|Location.Y=650|Name=3|Designator=3|PinPropagationDelay=0.000000E+000
|RECORD=2|OwnerIndex=1324|OwnerPartId=3|Electrical=4|PinConglomerate=48|PinLength=20|Location.X=260|Location.Y=650|Name=6|Designator=6|PinPropagationDelay=0.000000E+000
|RECORD=8|OwnerIndex=1324|IsNotAccesible=T|IndexInSheet=17|OwnerPartId=4|Location.X=243|Location.Y=650|Radius=2|SecondaryRadius=2|LineWidth=1|Color=16711680
|RECORD=8|OwnerIndex=1324|IsNotAccesible=T|IndexInSheet=18|OwnerPartId=4|Location.X=257|Location.Y=650|Radius=2|SecondaryRadius=2|LineWidth=1|Color=16711680
|RECORD=13|OwnerIndex=1324|IsNotAccesible=T|IndexInSheet=19|OwnerPartId=4|Location.X=245|Location.Y=651|Corner.X=255|Corner.Y=657|LineWidth=1|Color=16711680
|RECORD=2|OwnerIndex=1324|OwnerPartId=4|Electrical=4|PinConglomerate=50|PinLength=20|Location.X=240|Location.Y=650|Name=4|Designator=4|PinPropagationDelay=0.000000E+000
|RECORD=2|OwnerIndex=1324|OwnerPartId=4|Electrical=4|PinConglomerate=48|PinLength=20|Location.X=260|Location.Y=650|Name=5|Designator=5|PinPropagationDelay=0.000000E+000
|RECORD=41|OwnerIndex=1324|IndexInSheet=22|OwnerPartId=-1|Location.X=218|Location.Y=658|Color=8388608|FontID=3|IsHidden=T|Text=https://www.te.com/commerce/DocumentDelivery/DDEController?Action=showdoc&DocId=Customer+Drawing%7F1571983%7FC6%7Fpdf%7FEnglish%7FENG_CD_1571983_C6.pdf%7F1571983-4|Name=ComponentLink2URL
|RECORD=41|OwnerIndex=1324|IndexInSheet=23|OwnerPartId=-1|Location.X=218|Location.Y=658|Color=8388608|FontID=1|IsHidden=T|Text=SPST|Name=Throw Configuration
|RECORD=41|OwnerIndex=1324|IndexInSheet=24|OwnerPartId=-1|Location.X=218|Location.Y=658|Color=8388608|FontID=1|IsHidden=T|Text=Electromechanical|Name=Device Class L1
|RECORD=41|OwnerIndex=1324|IndexInSheet=25|OwnerPartId=-1|Location.X=218|Location.Y=658|Color=8388608|FontID=1|IsHidden=T|Text=0.1mm|Name=Standoff Height
|RECORD=41|OwnerIndex=1324|IndexInSheet=26|OwnerPartId=-1|Location.X=218|Location.Y=658|Color=8388608|FontID=1|IsHidden=T|Text=Yes|Name=Lead Free
|RECORD=41|OwnerIndex=1324|IndexInSheet=27|OwnerPartId=-1|Location.X=218|Location.Y=658|Color=8388608|FontID=1|IsHidden=T|Text=-30°C|Name=Temperature Range Low
|RECORD=41|OwnerIndex=1324|IndexInSheet=28|OwnerPartId=-1|Location.X=218|Location.Y=658|Color=8388608|FontID=1|IsHidden=T|Text=-30°C to +85°C|Name=Temperature
|RECORD=41|OwnerIndex=1324|IndexInSheet=29|OwnerPartId=-1|Location.X=218|Location.Y=658|Color=8388608|FontID=1|IsHidden=T|Text=1000Cycles|Name=Electromechanical Life
|RECORD=41|OwnerIndex=1324|IndexInSheet=30|OwnerPartId=-1|Location.X=218|Location.Y=658|Color=8388608|FontID=3|IsHidden=T|Text=https://octopart.com/1571983-4-te+connectivity-46507521|Name=Octopart
|RECORD=41|OwnerIndex=1324|IndexInSheet=31|OwnerPartId=-1|Location.X=218|Location.Y=658|Color=8388608|FontID=1|IsHidden=T|Text=TE Connectivity|Name=Manufacturer
|RECORD=41|OwnerIndex=1324|IndexInSheet=32|OwnerPartId=-1|Location.X=218|Location.Y=658|Color=8388608|FontID=1|IsHidden=T|Text=+85°C|Name=Temperature Range High
|RECORD=41|OwnerIndex=1324|IndexInSheet=33|OwnerPartId=-1|Location.X=218|Location.Y=658|Color=8388608|FontID=1|IsHidden=T|Text=1571983-4|Name=Package
|RECORD=41|OwnerIndex=1324|IndexInSheet=34|OwnerPartId=-1|Location.X=218|Location.Y=658|Color=8388608|FontID=1|IsHidden=T|Text=4|Name=Number Of Circuits
|RECORD=41|OwnerIndex=1324|IndexInSheet=35|OwnerPartId=-1|Location.X=218|Location.Y=658|Color=8388608|FontID=1|IsHidden=T|Text=2.56mm|Name=Height
|RECORD=41|OwnerIndex=1324|IndexInSheet=36|OwnerPartId=-1|Location.X=218|Location.Y=658|Color=8388608|FontID=1|IsHidden=T|Text=1571983-4|Name=Manufacturer Part Number
|RECORD=41|OwnerIndex=1324|IndexInSheet=37|OwnerPartId=-1|Location.X=218|Location.Y=658|Color=8388608|FontID=1|IsHidden=T|Text=25mA|Name=Contact Current Rating
|RECORD=41|OwnerIndex=1324|IndexInSheet=38|OwnerPartId=-1|Location.X=218|Location.Y=658|Color=8388608|FontID=1|IsHidden=T|Text=Datasheet|Name=ComponentLink2Description
|RECORD=41|OwnerIndex=1324|IndexInSheet=39|OwnerPartId=-1|Location.X=218|Location.Y=658|Color=8388608|FontID=1|IsHidden=T|Text=DIP Switches|Name=Device Class L3
|RECORD=41|OwnerIndex=1324|IndexInSheet=40|OwnerPartId=-1|Location.X=218|Location.Y=658|Color=8388608|FontID=1|IsHidden=T|Text=Switch|Name=Category
|RECORD=41|OwnerIndex=1324|IndexInSheet=41|OwnerPartId=-1|Location.X=218|Location.Y=658|Color=8388608|FontID=1|IsHidden=T|Text=100mO|Name=Contact Resistance
|RECORD=41|OwnerIndex=1324|IndexInSheet=42|OwnerPartId=-1|Location.X=218|Location.Y=658|Color=8388608|FontID=1|IsHidden=T|Text=Switches|Name=Device Class L2
|RECORD=41|OwnerIndex=1324|IndexInSheet=43|OwnerPartId=-1|Location.X=218|Location.Y=658|Color=8388608|FontID=1|IsHidden=T|Text=TRUE|Name=RoHS
|RECORD=41|OwnerIndex=1324|IndexInSheet=44|OwnerPartId=-1|Location.X=218|Location.Y=658|Color=8388608|FontID=1|IsHidden=T|Text=24V|Name=Voltage Rating Dc
|RECORD=41|OwnerIndex=1324|IndexInSheet=45|OwnerPartId=-1|Location.X=218|Location.Y=658|Color=8388608|FontID=1|IsHidden=T|Text=SWITCH SLIDE DIP SPST 25MA 24V|Name=Digikey Description
|RECORD=41|OwnerIndex=1324|IndexInSheet=46|OwnerPartId=-1|Location.X=218|Location.Y=658|Color=8388608|FontID=1|IsHidden=T|Text=No|Name=Automotive
|RECORD=34|OwnerIndex=1324|IndexInSheet=-1|OwnerPartId=-1|Location.X=241|Location.Y=658|Color=8388608|FontID=1|Text=SW1|Name=Designator|ReadOnlyState=1
|RECORD=41|OwnerIndex=1324|IndexInSheet=-1|OwnerPartId=1|Location.X=241|Location.Y=637|Color=8388608|FontID=1|Text=1571983-4|Name=Comment
|RECORD=44|OwnerIndex=1324
|RECORD=45|OwnerIndex=1382|IndexInSheet=-1|UseComponentLibrary=T|ModelName=FP-1571983-4-MFG|ModelType=PCBLIB|DatafileCount=1|ModelDatafileEntity0=FP-1571983-4-MFG|ModelDatafileKind0=PCBLib|IsCurrent=T|DatalinksLocked=T|DatabaseDatalinksLocked=T
|RECORD=46|OwnerIndex=1383
|RECORD=48|OwnerIndex=1383
|RECORD=1|LibReference=6123b3bffd52fd60b6df23d79e332fa|ComponentDescription=SWITCH SLIDE DIP SPST 25MA 24V|PartCount=5|DisplayModeCount=1|IndexInSheet=114|OwnerPartId=-1|Location.X=220|Location.Y=610|CurrentPartId=4|LibraryPath=*|SourceLibraryName=Altium Content Vault|TargetFileName=*|AreaColor=11599871|Color=128|PartIDLocked=T|DesignItemId=CMP-03400-000014-1|AllPinCount=8
|RECORD=2|OwnerIndex=1386|OwnerPartId=1|Electrical=4|PinConglomerate=50|PinLength=20|Location.X=240|Location.Y=610|Name=1|Designator=1|PinPropagationDelay=0.000000E+000
|RECORD=2|OwnerIndex=1386|OwnerPartId=1|Electrical=4|PinConglomerate=48|PinLength=20|Location.X=260|Location.Y=610|Name=8|Designator=8|PinPropagationDelay=0.000000E+000
|RECORD=8|OwnerIndex=1386|IsNotAccesible=T|IndexInSheet=2|OwnerPartId=1|Location.X=243|Location.Y=610|Radius=2|SecondaryRadius=2|LineWidth=1|Color=16711680
|RECORD=8|OwnerIndex=1386|IsNotAccesible=T|IndexInSheet=3|OwnerPartId=1|Location.X=257|Location.Y=610|Radius=2|SecondaryRadius=2|LineWidth=1|Color=16711680
|RECORD=13|OwnerIndex=1386|IsNotAccesible=T|IndexInSheet=4|OwnerPartId=1|Location.X=245|Location.Y=611|Corner.X=255|Corner.Y=617|LineWidth=1|Color=16711680
|RECORD=13|OwnerIndex=1386|IsNotAccesible=T|IndexInSheet=5|OwnerPartId=1|Location.X=240|Location.Y=610|Corner.X=237|Corner.Y=610|LineWidth=1|Color=16711680
|RECORD=13|OwnerIndex=1386|IsNotAccesible=T|IndexInSheet=6|OwnerPartId=1|Location.X=260|Location.Y=610|Corner.X=263|Corner.Y=610|LineWidth=1|Color=16711680
|RECORD=8|OwnerIndex=1386|IsNotAccesible=T|IndexInSheet=7|OwnerPartId=2|Location.X=243|Location.Y=610|Radius=2|SecondaryRadius=2|LineWidth=1|Color=16711680
|RECORD=8|OwnerIndex=1386|IsNotAccesible=T|IndexInSheet=8|OwnerPartId=2|Location.X=257|Location.Y=610|Radius=2|SecondaryRadius=2|LineWidth=1|Color=16711680
|RECORD=13|OwnerIndex=1386|IsNotAccesible=T|IndexInSheet=9|OwnerPartId=2|Location.X=245|Location.Y=611|Corner.X=255|Corner.Y=617|LineWidth=1|Color=16711680
|RECORD=2|OwnerIndex=1386|OwnerPartId=2|Electrical=4|PinConglomerate=50|PinLength=20|Location.X=240|Location.Y=610|Name=2|Designator=2|PinPropagationDelay=0.000000E+000
|RECORD=2|OwnerIndex=1386|OwnerPartId=2|Electrical=4|PinConglomerate=48|PinLength=20|Location.X=260|Location.Y=610|Name=7|Designator=7|PinPropagationDelay=0.000000E+000
|RECORD=8|OwnerIndex=1386|IsNotAccesible=T|IndexInSheet=12|OwnerPartId=3|Location.X=243|Location.Y=610|Radius=2|SecondaryRadius=2|LineWidth=1|Color=16711680
|RECORD=8|OwnerIndex=1386|IsNotAccesible=T|IndexInSheet=13|OwnerPartId=3|Location.X=257|Location.Y=610|Radius=2|SecondaryRadius=2|LineWidth=1|Color=16711680
|RECORD=13|OwnerIndex=1386|IsNotAccesible=T|IndexInSheet=14|OwnerPartId=3|Location.X=245|Location.Y=611|Corner.X=255|Corner.Y=617|LineWidth=1|Color=16711680
|RECORD=2|OwnerIndex=1386|OwnerPartId=3|Electrical=4|PinConglomerate=50|PinLength=20|Location.X=240|Location.Y=610|Name=3|Designator=3|PinPropagationDelay=0.000000E+000
|RECORD=2|OwnerIndex=1386|OwnerPartId=3|Electrical=4|PinConglomerate=48|PinLength=20|Location.X=260|Location.Y=610|Name=6|Designator=6|PinPropagationDelay=0.000000E+000
|RECORD=8|OwnerIndex=1386|IsNotAccesible=T|IndexInSheet=17|OwnerPartId=4|Location.X=243|Location.Y=610|Radius=2|SecondaryRadius=2|LineWidth=1|Color=16711680
|RECORD=8|OwnerIndex=1386|IsNotAccesible=T|IndexInSheet=18|OwnerPartId=4|Location.X=257|Location.Y=610|Radius=2|SecondaryRadius=2|LineWidth=1|Color=16711680
|RECORD=13|OwnerIndex=1386|IsNotAccesible=T|IndexInSheet=19|OwnerPartId=4|Location.X=245|Location.Y=611|Corner.X=255|Corner.Y=617|LineWidth=1|Color=16711680
|RECORD=2|OwnerIndex=1386|OwnerPartId=4|Electrical=4|PinConglomerate=50|PinLength=20|Location.X=240|Location.Y=610|Name=4|Designator=4|PinPropagationDelay=0.000000E+000
|RECORD=2|OwnerIndex=1386|OwnerPartId=4|Electrical=4|PinConglomerate=48|PinLength=20|Location.X=260|Location.Y=610|Name=5|Designator=5|PinPropagationDelay=0.000000E+000
|RECORD=41|OwnerIndex=1386|IndexInSheet=22|OwnerPartId=-1|Location.X=218|Location.Y=618|Color=8388608|FontID=3|IsHidden=T|Text=https://www.te.com/commerce/DocumentDelivery/DDEController?Action=showdoc&DocId=Customer+Drawing%7F1571983%7FC6%7Fpdf%7FEnglish%7FENG_CD_1571983_C6.pdf%7F1571983-4|Name=ComponentLink2URL
|RECORD=41|OwnerIndex=1386|IndexInSheet=23|OwnerPartId=-1|Location.X=218|Location.Y=618|Color=8388608|FontID=1|IsHidden=T|Text=SPST|Name=Throw Configuration
|RECORD=41|OwnerIndex=1386|IndexInSheet=24|OwnerPartId=-1|Location.X=218|Location.Y=618|Color=8388608|FontID=1|IsHidden=T|Text=Electromechanical|Name=Device Class L1
|RECORD=41|OwnerIndex=1386|IndexInSheet=25|OwnerPartId=-1|Location.X=218|Location.Y=618|Color=8388608|FontID=1|IsHidden=T|Text=0.1mm|Name=Standoff Height
|RECORD=41|OwnerIndex=1386|IndexInSheet=26|OwnerPartId=-1|Location.X=218|Location.Y=618|Color=8388608|FontID=1|IsHidden=T|Text=Yes|Name=Lead Free
|RECORD=41|OwnerIndex=1386|IndexInSheet=27|OwnerPartId=-1|Location.X=218|Location.Y=618|Color=8388608|FontID=1|IsHidden=T|Text=-30°C|Name=Temperature Range Low
|RECORD=41|OwnerIndex=1386|IndexInSheet=28|OwnerPartId=-1|Location.X=218|Location.Y=618|Color=8388608|FontID=1|IsHidden=T|Text=-30°C to +85°C|Name=Temperature
|RECORD=41|OwnerIndex=1386|IndexInSheet=29|OwnerPartId=-1|Location.X=218|Location.Y=618|Color=8388608|FontID=1|IsHidden=T|Text=1000Cycles|Name=Electromechanical Life
|RECORD=41|OwnerIndex=1386|IndexInSheet=30|OwnerPartId=-1|Location.X=218|Location.Y=618|Color=8388608|FontID=3|IsHidden=T|Text=https://octopart.com/1571983-4-te+connectivity-46507521|Name=Octopart
|RECORD=41|OwnerIndex=1386|IndexInSheet=31|OwnerPartId=-1|Location.X=218|Location.Y=618|Color=8388608|FontID=1|IsHidden=T|Text=TE Connectivity|Name=Manufacturer
|RECORD=41|OwnerIndex=1386|IndexInSheet=32|OwnerPartId=-1|Location.X=218|Location.Y=618|Color=8388608|FontID=1|IsHidden=T|Text=+85°C|Name=Temperature Range High
|RECORD=41|OwnerIndex=1386|IndexInSheet=33|OwnerPartId=-1|Location.X=218|Location.Y=618|Color=8388608|FontID=1|IsHidden=T|Text=1571983-4|Name=Package
|RECORD=41|OwnerIndex=1386|IndexInSheet=34|OwnerPartId=-1|Location.X=218|Location.Y=618|Color=8388608|FontID=1|IsHidden=T|Text=4|Name=Number Of Circuits
|RECORD=41|OwnerIndex=1386|IndexInSheet=35|OwnerPartId=-1|Location.X=218|Location.Y=618|Color=8388608|FontID=1|IsHidden=T|Text=2.56mm|Name=Height
|RECORD=41|OwnerIndex=1386|IndexInSheet=36|OwnerPartId=-1|Location.X=218|Location.Y=618|Color=8388608|FontID=1|IsHidden=T|Text=1571983-4|Name=Manufacturer Part Number
|RECORD=41|OwnerIndex=1386|IndexInSheet=37|OwnerPartId=-1|Location.X=218|Location.Y=618|Color=8388608|FontID=1|IsHidden=T|Text=25mA|Name=Contact Current Rating
|RECORD=41|OwnerIndex=1386|IndexInSheet=38|OwnerPartId=-1|Location.X=218|Location.Y=618|Color=8388608|FontID=1|IsHidden=T|Text=Datasheet|Name=ComponentLink2Description
|RECORD=41|OwnerIndex=1386|IndexInSheet=39|OwnerPartId=-1|Location.X=218|Location.Y=618|Color=8388608|FontID=1|IsHidden=T|Text=DIP Switches|Name=Device Class L3
|RECORD=41|OwnerIndex=1386|IndexInSheet=40|OwnerPartId=-1|Location.X=218|Location.Y=618|Color=8388608|FontID=1|IsHidden=T|Text=Switch|Name=Category
|RECORD=41|OwnerIndex=1386|IndexInSheet=41|OwnerPartId=-1|Location.X=218|Location.Y=618|Color=8388608|FontID=1|IsHidden=T|Text=100mO|Name=Contact Resistance
|RECORD=41|OwnerIndex=1386|IndexInSheet=42|OwnerPartId=-1|Location.X=218|Location.Y=618|Color=8388608|FontID=1|IsHidden=T|Text=Switches|Name=Device Class L2
|RECORD=41|OwnerIndex=1386|IndexInSheet=43|OwnerPartId=-1|Location.X=218|Location.Y=618|Color=8388608|FontID=1|IsHidden=T|Text=TRUE|Name=RoHS
|RECORD=41|OwnerIndex=1386|IndexInSheet=44|OwnerPartId=-1|Location.X=218|Location.Y=618|Color=8388608|FontID=1|IsHidden=T|Text=24V|Name=Voltage Rating Dc
|RECORD=41|OwnerIndex=1386|IndexInSheet=45|OwnerPartId=-1|Location.X=218|Location.Y=618|Color=8388608|FontID=1|IsHidden=T|Text=SWITCH SLIDE DIP SPST 25MA 24V|Name=Digikey Description
|RECORD=41|OwnerIndex=1386|IndexInSheet=46|OwnerPartId=-1|Location.X=218|Location.Y=618|Color=8388608|FontID=1|IsHidden=T|Text=No|Name=Automotive
|RECORD=34|OwnerIndex=1386|IndexInSheet=-1|OwnerPartId=-1|Location.X=241|Location.Y=618|Color=8388608|FontID=1|Text=SW1|Name=Designator|ReadOnlyState=1
|RECORD=41|OwnerIndex=1386|IndexInSheet=-1|OwnerPartId=1|Location.X=241|Location.Y=597|Color=8388608|FontID=1|Text=1571983-4|Name=Comment
|RECORD=44|OwnerIndex=1386
|RECORD=45|OwnerIndex=1444|IndexInSheet=-1|UseComponentLibrary=T|ModelName=FP-1571983-4-MFG|ModelType=PCBLIB|DatafileCount=1|ModelDatafileEntity0=FP-1571983-4-MFG|ModelDatafileKind0=PCBLib|IsCurrent=T|DatalinksLocked=T|DatabaseDatalinksLocked=T
|RECORD=46|OwnerIndex=1445
|RECORD=48|OwnerIndex=1445
|RECORD=1|LibReference=RES|PartCount=2|DisplayModeCount=2|IndexInSheet=115|OwnerPartId=-1|Location.X=370|Location.Y=770|Orientation=3|CurrentPartId=1|SourceLibraryName=Altium Content Vault|TargetFileName=*|AreaColor=11599871|Color=128|PartIDLocked=F|DesignItemId=CMP-2002-07353-1|AllPinCount=2
|RECORD=2|OwnerIndex=1448|OwnerPartId=1|OwnerPartDisplayMode=1|FormalType=1|Electrical=4|PinConglomerate=35|PinLength=10|Location.X=360|Location.Y=750|Name=2|Designator=2|PinPropagationDelay=0.000000E+000
|RECORD=2|OwnerIndex=1448|OwnerPartId=1|OwnerPartDisplayMode=1|FormalType=1|Electrical=4|PinConglomerate=33|PinLength=10|Location.X=360|Location.Y=770|Name=1|Designator=1|PinPropagationDelay=0.000000E+000
|RECORD=14|OwnerIndex=1448|IsNotAccesible=T|IndexInSheet=2|OwnerPartId=1|OwnerPartDisplayMode=1|Location.X=356|Location.Y=750|Corner.X=364|Corner.Y=770|LineWidth=1|Color=16711680|AreaColor=11599871
|RECORD=2|OwnerIndex=1448|OwnerPartId=1|FormalType=1|Electrical=4|PinConglomerate=35|PinLength=10|Location.X=360|Location.Y=750|Name=2|Designator=2|PinPropagationDelay=0.000000E+000
|RECORD=2|OwnerIndex=1448|OwnerPartId=1|FormalType=1|Electrical=4|PinConglomerate=33|PinLength=10|Location.X=360|Location.Y=770|Name=1|Designator=1|PinPropagationDelay=0.000000E+000
|RECORD=6|OwnerIndex=1448|IsNotAccesible=T|IndexInSheet=5|OwnerPartId=1|LineWidth=1|Color=16711680|LocationCount=10|X1=360|Y1=750|X2=360|Y2=754|X3=358|Y3=755|X4=362|Y4=757|X5=358|Y5=759|X6=362|Y6=761|X7=358|Y7=763|X8=362|Y8=765|X9=360|Y9=766|X10=360|Y10=770
|RECORD=41|OwnerIndex=1448|IndexInSheet=6|OwnerPartId=-1|Location.X=357|Location.Y=782|Color=8388608|FontID=1|IsHidden=T|Text=RC0402FR-0710KL|Name=Part Number
|RECORD=41|OwnerIndex=1448|IndexInSheet=7|OwnerPartId=-1|Location.X=357|Location.Y=782|Color=8388608|FontID=1|IsHidden=T|Text=Yageo / Phycomp|Name=Manufacturer
|RECORD=34|OwnerIndex=1448|IndexInSheet=-1|OwnerPartId=-1|Location.X=360|Location.Y=740|Orientation=1|Color=8388608|FontID=2|Text=R140|Name=Designator|ReadOnlyState=1
|RECORD=41|OwnerIndex=1448|IndexInSheet=-1|OwnerPartId=-1|Location.X=370|Location.Y=740|Orientation=1|Color=8388608|FontID=2|Text=10K_1%_0402|Name=Comment
|RECORD=44|OwnerIndex=1448
|RECORD=45|OwnerIndex=1463|IndexInSheet=-1|Description=Chip Resistor, 2-Leads, Body 1.00x0.50mm, IPC High Density|UseComponentLibrary=T|ModelName=RESC1005X40X25LL05T10|ModelType=PCBLIB|DatafileCount=1|ModelDatafileEntity0=RESC1005X40X25LL05T10|ModelDatafileKind0=PCBLib|IsCurrent=T|DatalinksLocked=T|DatabaseDatalinksLocked=T
|RECORD=46|OwnerIndex=1464
|RECORD=48|OwnerIndex=1464
|RECORD=41|OwnerIndex=1466|IndexInSheet=-1|OwnerPartId=-1|Color=8388608|FontID=1|IsHidden=T|Text=2D|Name=Available Preview Images
|RECORD=45|OwnerIndex=1463|IndexInSheet=-1|Description=Chip Resistor, 2-Leads, Body 1.00x0.50mm, IPC Low Density|UseComponentLibrary=T|ModelName=RESC1005X40X25ML05T10|ModelType=PCBLIB|DatafileCount=1|ModelDatafileEntity0=RESC1005X40X25ML05T10|ModelDatafileKind0=PCBLib|DatalinksLocked=T|DatabaseDatalinksLocked=T
|RECORD=46|OwnerIndex=1468
|RECORD=48|OwnerIndex=1468
|RECORD=41|OwnerIndex=1470|IndexInSheet=-1|OwnerPartId=-1|Color=8388608|FontID=1|IsHidden=T|Text=2D|Name=Available Preview Images
|RECORD=45|OwnerIndex=1463|IndexInSheet=-1|Description=Chip Resistor, 2-Leads, Body 1.00x0.50mm, IPC Medium Density|UseComponentLibrary=T|ModelName=RESC1005X40X25NL05T10|ModelType=PCBLIB|DatafileCount=1|ModelDatafileEntity0=RESC1005X40X25NL05T10|ModelDatafileKind0=PCBLib|DatalinksLocked=T|DatabaseDatalinksLocked=T
|RECORD=46|OwnerIndex=1472
|RECORD=48|OwnerIndex=1472
|RECORD=41|OwnerIndex=1474|IndexInSheet=-1|OwnerPartId=-1|Color=8388608|FontID=1|IsHidden=T|Text=2D|Name=Available Preview Images
|RECORD=17|IndexInSheet=116|OwnerPartId=-1|Style=1|ShowNetName=T|Location.X=420|Location.Y=570|Color=255|FontID=1|Text=DIP_SW_GPS2_SEL|IsCrossSheetConnector=T
|RECORD=1|LibReference=SW-SPST-4_C|ComponentDescription=Surface Mount DIP Switch Auto Placeable, -55 to 85 degC, 4-Pin SMD, RoHS, Tube|PartCount=2|DisplayModeCount=1|IndexInSheet=117|OwnerPartId=-1|Location.X=240|Location.Y=580|CurrentPartId=1|LibraryPath=*|SourceLibraryName=Altium Content Vault|TargetFileName=*|AreaColor=11599871|Color=128|PartIDLocked=T|DesignItemId=CMP-2000-05532-1|AllPinCount=4
|RECORD=2|OwnerIndex=1477|OwnerPartId=1|FormalType=1|Electrical=4|PinConglomerate=50|PinLength=20|Location.X=240|Location.Y=570|Name=1|Designator=1|PinPropagationDelay=0.000000E+000
|RECORD=2|OwnerIndex=1477|OwnerPartId=1|FormalType=1|Electrical=4|PinConglomerate=48|PinLength=20|Location.X=260|Location.Y=570|Name=4|Designator=4|PinPropagationDelay=0.000000E+000
|RECORD=2|OwnerIndex=1477|OwnerPartId=1|FormalType=1|Electrical=4|PinConglomerate=50|PinLength=20|Location.X=240|Location.Y=560|Name=2|Designator=2|PinPropagationDelay=0.000000E+000
|RECORD=2|OwnerIndex=1477|OwnerPartId=1|FormalType=1|Electrical=4|PinConglomerate=48|PinLength=20|Location.X=260|Location.Y=560|Name=3|Designator=3|PinPropagationDelay=0.000000E+000
|RECORD=12|OwnerIndex=1477|IsNotAccesible=T|IndexInSheet=4|OwnerPartId=1|Location.X=242|Location.Y=570|Radius=2|LineWidth=1|EndAngle=360.000|Color=16711680
|RECORD=12|OwnerIndex=1477|IsNotAccesible=T|IndexInSheet=5|OwnerPartId=1|Location.X=242|Location.Y=560|Radius=2|LineWidth=1|EndAngle=360.000|Color=16711680
|RECORD=12|OwnerIndex=1477|IsNotAccesible=T|IndexInSheet=6|OwnerPartId=1|Location.X=258|Location.Y=560|Radius=2|LineWidth=1|EndAngle=360.000|Color=16711680
|RECORD=12|OwnerIndex=1477|IsNotAccesible=T|IndexInSheet=7|OwnerPartId=1|Location.X=258|Location.Y=570|Radius=2|LineWidth=1|EndAngle=360.000|Color=16711680
|RECORD=6|OwnerIndex=1477|IsNotAccesible=T|IndexInSheet=8|OwnerPartId=1|LineWidth=1|Color=16711680|LocationCount=2|X1=244|Y1=570|X2=258|Y2=576
|RECORD=6|OwnerIndex=1477|IsNotAccesible=T|IndexInSheet=9|OwnerPartId=1|LineWidth=1|Color=16711680|LocationCount=2|X1=244|Y1=560|X2=258|Y2=566
|RECORD=41|OwnerIndex=1477|IndexInSheet=10|OwnerPartId=-1|Location.X=218|Location.Y=595|Color=8388608|FontID=1|IsHidden=T|Text=Dip|Name=Type
|RECORD=41|OwnerIndex=1477|IndexInSheet=11|OwnerPartId=-1|Location.X=218|Location.Y=595|Color=8388608|FontID=1|IsHidden=T|Text=Sealed|Name=Sealed Option
|RECORD=41|OwnerIndex=1477|IndexInSheet=12|OwnerPartId=-1|Location.X=218|Location.Y=595|Color=8388608|FontID=1|IsHidden=T|Text=219-2LPST|Name=Package Reference
|RECORD=41|OwnerIndex=1477|IndexInSheet=13|OwnerPartId=-1|Location.X=218|Location.Y=595|Color=8388608|FontID=1|IsHidden=T|Text=SPST|Name=Circuitry
|RECORD=41|OwnerIndex=1477|IndexInSheet=14|OwnerPartId=-1|Location.X=218|Location.Y=595|Color=8388608|FontID=1|IsHidden=T|Text=SurfaceMount|Name=Mounting Technology
|RECORD=41|OwnerIndex=1477|IndexInSheet=15|OwnerPartId=-1|Location.X=218|Location.Y=595|Color=8388608|FontID=1|IsHidden=T|Text=12/2008|Name=Datasheet Version
|RECORD=41|OwnerIndex=1477|IndexInSheet=16|OwnerPartId=-1|Location.X=218|Location.Y=595|Color=8388608|FontID=1|IsHidden=T|Text=CTS Corporation|Name=Manufacturer
|RECORD=41|OwnerIndex=1477|IndexInSheet=17|OwnerPartId=-1|Location.X=218|Location.Y=595|Color=8388608|FontID=1|IsHidden=T|Text=2|Name=No of Positions
|RECORD=41|OwnerIndex=1477|IndexInSheet=18|OwnerPartId=-1|Location.X=218|Location.Y=595|Color=8388608|FontID=1|IsHidden=T|Text=4-Pin Surface Mount Device, Body 6.7 x 6.55 mm|Name=Package Description
|RECORD=41|OwnerIndex=1477|IndexInSheet=19|OwnerPartId=-1|Location.X=218|Location.Y=595|Color=8388608|FontID=3|IsHidden=T|Text=http://www.ctscorp.com/wp-content/uploads/2016/01/219-Dec-30-2008.pdf|Name=Datasheet URL
|RECORD=41|OwnerIndex=1477|IndexInSheet=20|OwnerPartId=-1|Location.X=218|Location.Y=595|Color=8388608|FontID=1|IsHidden=T|Text=GullWing|Name=Termination Style
|RECORD=41|OwnerIndex=1477|IndexInSheet=21|OwnerPartId=-1|Location.X=218|Location.Y=595|Color=8388608|FontID=1|IsHidden=T|Text=LowProfile|Name=Actuator Style
|RECORD=41|OwnerIndex=1477|IndexInSheet=22|OwnerPartId=-1|Location.X=218|Location.Y=595|Color=8388608|FontID=3|IsHidden=T|Text=http://www.ctscorp.com/|Name=Manufacturer URL
|RECORD=34|OwnerIndex=1477|IndexInSheet=-1|OwnerPartId=-1|Location.X=240|Location.Y=577|Color=8388608|FontID=1|Text=SW2|Name=Designator|ReadOnlyState=1
|RECORD=41|OwnerIndex=1477|IndexInSheet=-1|OwnerPartId=-1|Location.X=240|Location.Y=547|Color=8388608|FontID=1|Text=219-2LPST|Name=Comment
|RECORD=44|OwnerIndex=1477
|RECORD=45|OwnerIndex=1507|IndexInSheet=-1|Description=SMD, 4-Leads, Body 6.706x6.553mm, Pitch 2.54mm|UseComponentLibrary=T|ModelName=CTS-219-2LPST_V|ModelType=PCBLIB|DatafileCount=1|ModelDatafileEntity0=CTS-219-2LPST_V|ModelDatafileKind0=PCBLib|IsCurrent=T|DatalinksLocked=T|DatabaseDatalinksLocked=T
|RECORD=46|OwnerIndex=1508
|RECORD=48|OwnerIndex=1508
|RECORD=41|OwnerIndex=1510|IndexInSheet=-1|OwnerPartId=-1|Color=8388608|FontID=1|IsHidden=T|Text=2D|Name=Available Preview Images
|RECORD=17|IndexInSheet=118|OwnerPartId=-1|Style=1|ShowNetName=T|Location.X=420|Location.Y=560|Color=255|FontID=1|Text=DIP_SW_GPS1_SEL|IsCrossSheetConnector=T
|RECORD=1|LibReference=RES|PartCount=2|DisplayModeCount=2|IndexInSheet=119|OwnerPartId=-1|Location.X=390|Location.Y=770|Orientation=3|CurrentPartId=1|SourceLibraryName=Altium Content Vault|TargetFileName=*|AreaColor=11599871|Color=128|PartIDLocked=F|DesignItemId=CMP-2002-07353-1|AllPinCount=2
|RECORD=2|OwnerIndex=1513|OwnerPartId=1|OwnerPartDisplayMode=1|FormalType=1|Electrical=4|PinConglomerate=35|PinLength=10|Location.X=380|Location.Y=750|Name=2|Designator=2|PinPropagationDelay=0.000000E+000
|RECORD=2|OwnerIndex=1513|OwnerPartId=1|OwnerPartDisplayMode=1|FormalType=1|Electrical=4|PinConglomerate=33|PinLength=10|Location.X=380|Location.Y=770|Name=1|Designator=1|PinPropagationDelay=0.000000E+000
|RECORD=14|OwnerIndex=1513|IsNotAccesible=T|IndexInSheet=2|OwnerPartId=1|OwnerPartDisplayMode=1|Location.X=376|Location.Y=750|Corner.X=384|Corner.Y=770|LineWidth=1|Color=16711680|AreaColor=11599871
|RECORD=2|OwnerIndex=1513|OwnerPartId=1|FormalType=1|Electrical=4|PinConglomerate=35|PinLength=10|Location.X=380|Location.Y=750|Name=2|Designator=2|PinPropagationDelay=0.000000E+000
|RECORD=2|OwnerIndex=1513|OwnerPartId=1|FormalType=1|Electrical=4|PinConglomerate=33|PinLength=10|Location.X=380|Location.Y=770|Name=1|Designator=1|PinPropagationDelay=0.000000E+000
|RECORD=6|OwnerIndex=1513|IsNotAccesible=T|IndexInSheet=5|OwnerPartId=1|LineWidth=1|Color=16711680|LocationCount=10|X1=380|Y1=750|X2=380|Y2=754|X3=378|Y3=755|X4=382|Y4=757|X5=378|Y5=759|X6=382|Y6=761|X7=378|Y7=763|X8=382|Y8=765|X9=380|Y9=766|X10=380|Y10=770
|RECORD=41|OwnerIndex=1513|IndexInSheet=6|OwnerPartId=-1|Location.X=377|Location.Y=782|Color=8388608|FontID=1|IsHidden=T|Text=RC0402FR-0710KL|Name=Part Number
|RECORD=41|OwnerIndex=1513|IndexInSheet=7|OwnerPartId=-1|Location.X=377|Location.Y=782|Color=8388608|FontID=1|IsHidden=T|Text=Yageo / Phycomp|Name=Manufacturer
|RECORD=34|OwnerIndex=1513|IndexInSheet=-1|OwnerPartId=-1|Location.X=380|Location.Y=740|Orientation=1|Color=8388608|FontID=2|Text=R141|Name=Designator|ReadOnlyState=1
|RECORD=41|OwnerIndex=1513|IndexInSheet=-1|OwnerPartId=-1|Location.X=390|Location.Y=740|Orientation=1|Color=8388608|FontID=2|Text=10K_1%_0402|Name=Comment
|RECORD=44|OwnerIndex=1513
|RECORD=45|OwnerIndex=1528|IndexInSheet=-1|Description=Chip Resistor, 2-Leads, Body 1.00x0.50mm, IPC High Density|UseComponentLibrary=T|ModelName=RESC1005X40X25LL05T10|ModelType=PCBLIB|DatafileCount=1|ModelDatafileEntity0=RESC1005X40X25LL05T10|ModelDatafileKind0=PCBLib|IsCurrent=T|DatalinksLocked=T|DatabaseDatalinksLocked=T
|RECORD=46|OwnerIndex=1529
|RECORD=48|OwnerIndex=1529
|RECORD=41|OwnerIndex=1531|IndexInSheet=-1|OwnerPartId=-1|Color=8388608|FontID=1|IsHidden=T|Text=2D|Name=Available Preview Images
|RECORD=45|OwnerIndex=1528|IndexInSheet=-1|Description=Chip Resistor, 2-Leads, Body 1.00x0.50mm, IPC Low Density|UseComponentLibrary=T|ModelName=RESC1005X40X25ML05T10|ModelType=PCBLIB|DatafileCount=1|ModelDatafileEntity0=RESC1005X40X25ML05T10|ModelDatafileKind0=PCBLib|DatalinksLocked=T|DatabaseDatalinksLocked=T
|RECORD=46|OwnerIndex=1533
|RECORD=48|OwnerIndex=1533
|RECORD=41|OwnerIndex=1535|IndexInSheet=-1|OwnerPartId=-1|Color=8388608|FontID=1|IsHidden=T|Text=2D|Name=Available Preview Images
|RECORD=45|OwnerIndex=1528|IndexInSheet=-1|Description=Chip Resistor, 2-Leads, Body 1.00x0.50mm, IPC Medium Density|UseComponentLibrary=T|ModelName=RESC1005X40X25NL05T10|ModelType=PCBLIB|DatafileCount=1|ModelDatafileEntity0=RESC1005X40X25NL05T10|ModelDatafileKind0=PCBLib|DatalinksLocked=T|DatabaseDatalinksLocked=T
|RECORD=46|OwnerIndex=1537
|RECORD=48|OwnerIndex=1537
|RECORD=41|OwnerIndex=1539|IndexInSheet=-1|OwnerPartId=-1|Color=8388608|FontID=1|IsHidden=T|Text=2D|Name=Available Preview Images
|RECORD=27|IndexInSheet=120|OwnerPartId=-1|LineWidth=1|Color=8388608|LocationCount=2|X1=300|Y1=780|X2=300|Y2=800
|RECORD=27|IndexInSheet=121|OwnerPartId=-1|LineWidth=1|Color=8388608|LocationCount=2|X1=300|Y1=730|X2=300|Y2=740
|RECORD=27|IndexInSheet=122|OwnerPartId=-1|LineWidth=1|Color=8388608|LocationCount=2|X1=180|Y1=690|X2=220|Y2=690
|RECORD=27|IndexInSheet=123|OwnerPartId=-1|LineWidth=1|Color=8388608|LocationCount=2|X1=180|Y1=650|X2=220|Y2=650
|RECORD=27|IndexInSheet=124|OwnerPartId=-1|LineWidth=1|Color=8388608|LocationCount=2|X1=320|Y1=690|X2=320|Y2=740
|RECORD=27|IndexInSheet=125|OwnerPartId=-1|LineWidth=1|Color=8388608|LocationCount=2|X1=300|Y1=780|X2=320|Y2=780
|RECORD=27|IndexInSheet=126|OwnerPartId=-1|LineWidth=1|Color=8388608|LocationCount=2|X1=320|Y1=780|X2=340|Y2=780
|RECORD=27|IndexInSheet=127|OwnerPartId=-1|LineWidth=1|Color=8388608|LocationCount=2|X1=340|Y1=740|X2=340|Y2=650
|RECORD=27|IndexInSheet=128|OwnerPartId=-1|LineWidth=1|Color=8388608|LocationCount=2|X1=170|Y1=310|X2=180|Y2=310
|RECORD=27|IndexInSheet=129|OwnerPartId=-1|LineWidth=1|Color=8388608|LocationCount=2|X1=220|Y1=310|X2=230|Y2=310
|RECORD=27|IndexInSheet=130|OwnerPartId=-1|LineWidth=1|Color=8388608|LocationCount=3|X1=290|Y1=310|X2=310|Y2=310|X3=310|Y3=330
|RECORD=27|IndexInSheet=131|OwnerPartId=-1|LineWidth=1|Color=8388608|LocationCount=2|X1=170|Y1=410|X2=180|Y2=410
|RECORD=27|IndexInSheet=132|OwnerPartId=-1|LineWidth=1|Color=8388608|LocationCount=2|X1=220|Y1=410|X2=230|Y2=410
|RECORD=27|IndexInSheet=133|OwnerPartId=-1|LineWidth=1|Color=8388608|LocationCount=3|X1=290|Y1=410|X2=310|Y2=410|X3=310|Y3=430
|RECORD=27|IndexInSheet=134|OwnerPartId=-1|LineWidth=1|Color=8388608|LocationCount=2|X1=170|Y1=200|X2=180|Y2=200
|RECORD=27|IndexInSheet=135|OwnerPartId=-1|LineWidth=1|Color=8388608|LocationCount=2|X1=220|Y1=200|X2=230|Y2=200
|RECORD=27|IndexInSheet=136|OwnerPartId=-1|LineWidth=1|Color=8388608|LocationCount=3|X1=290|Y1=200|X2=310|Y2=200|X3=310|Y3=220
|RECORD=27|IndexInSheet=137|OwnerPartId=-1|LineWidth=1|Color=8388608|LocationCount=2|X1=920|Y1=620|X2=900|Y2=620
|RECORD=27|IndexInSheet=138|OwnerPartId=-1|LineWidth=1|Color=8388608|LocationCount=4|X1=860|Y1=830|X2=890|Y2=830|X3=890|Y3=770|X4=920|Y4=770
|RECORD=27|IndexInSheet=139|OwnerPartId=-1|LineWidth=1|Color=8388608|LocationCount=2|X1=860|Y1=770|X2=860|Y2=780
|RECORD=27|IndexInSheet=140|OwnerPartId=-1|LineWidth=1|Color=8388608|LocationCount=3|X1=920|Y1=660|X2=900|Y2=660|X3=900|Y3=670
|RECORD=27|IndexInSheet=141|OwnerPartId=-1|LineWidth=1|Color=8388608|LocationCount=3|X1=1060|Y1=620|X2=1070|Y2=620|X3=1070|Y3=610
|RECORD=27|IndexInSheet=142|OwnerPartId=-1|LineWidth=1|Color=8388608|LocationCount=2|X1=820|Y1=750|X2=920|Y2=750
|RECORD=27|IndexInSheet=143|OwnerPartId=-1|LineWidth=1|Color=8388608|LocationCount=2|X1=820|Y1=710|X2=920|Y2=710
|RECORD=27|IndexInSheet=144|OwnerPartId=-1|LineWidth=1|Color=8388608|LocationCount=2|X1=820|Y1=690|X2=920|Y2=690
|RECORD=27|IndexInSheet=145|OwnerPartId=-1|LineWidth=1|Color=8388608|LocationCount=2|X1=820|Y1=730|X2=920|Y2=730
|RECORD=27|IndexInSheet=146|OwnerPartId=-1|LineWidth=1|Color=8388608|LocationCount=2|X1=710|Y1=750|X2=780|Y2=750
|RECORD=27|IndexInSheet=147|OwnerPartId=-1|LineWidth=1|Color=8388608|LocationCount=2|X1=780|Y1=710|X2=710|Y2=710
|RECORD=27|IndexInSheet=148|OwnerPartId=-1|LineWidth=1|Color=8388608|LocationCount=2|X1=740|Y1=730|X2=780|Y2=730
|RECORD=27|IndexInSheet=149|OwnerPartId=-1|LineWidth=1|Color=8388608|LocationCount=2|X1=780|Y1=690|X2=740|Y2=690
|RECORD=27|IndexInSheet=150|OwnerPartId=-1|LineWidth=1|Color=8388608|LocationCount=3|X1=1040|Y1=880|X2=1080|Y2=880|X3=1080|Y3=750
|RECORD=27|IndexInSheet=151|OwnerPartId=-1|LineWidth=1|Color=8388608|LocationCount=3|X1=1040|Y1=860|X2=1070|Y2=860|X3=1070|Y3=710
|RECORD=27|IndexInSheet=152|OwnerPartId=-1|LineWidth=1|Color=8388608|LocationCount=2|X1=1000|Y1=860|X2=970|Y2=860
|RECORD=27|IndexInSheet=153|OwnerPartId=-1|LineWidth=1|Color=8388608|LocationCount=2|X1=1000|Y1=880|X2=970|Y2=880
|RECORD=27|IndexInSheet=154|OwnerPartId=-1|LineWidth=1|Color=8388608|LocationCount=3|X1=810|Y1=670|X2=900|Y2=670|X3=920|Y3=670
|RECORD=27|IndexInSheet=155|OwnerPartId=-1|LineWidth=1|Color=8388608|LocationCount=4|X1=920|Y1=640|X2=900|Y2=640|X3=900|Y3=620|X4=900|Y4=610
|RECORD=27|IndexInSheet=156|OwnerPartId=-1|LineWidth=1|Color=8388608|LocationCount=3|X1=1110|Y1=750|X2=1080|Y2=750|X3=1060|Y3=750
|RECORD=27|IndexInSheet=157|OwnerPartId=-1|LineWidth=1|Color=8388608|LocationCount=4|X1=860|Y1=800|X2=860|Y2=830|X3=800|Y3=830|X4=800|Y4=850
|RECORD=27|IndexInSheet=158|OwnerPartId=-1|LineWidth=1|Color=8388608|LocationCount=3|X1=1060|Y1=710|X2=1070|Y2=710|X3=1110|Y3=710
|RECORD=27|IndexInSheet=159|OwnerPartId=-1|LineWidth=1|Color=8388608|LocationCount=3|X1=860|Y1=310|X2=860|Y2=370|X3=910|Y3=370
|RECORD=27|IndexInSheet=160|OwnerPartId=-1|LineWidth=1|Color=8388608|LocationCount=3|X1=840|Y1=310|X2=840|Y2=380|X3=910|Y3=380
|RECORD=27|IndexInSheet=161|OwnerPartId=-1|LineWidth=1|Color=8388608|LocationCount=3|X1=820|Y1=310|X2=820|Y2=390|X3=910|Y3=390
|RECORD=27|IndexInSheet=162|OwnerPartId=-1|LineWidth=1|Color=8388608|LocationCount=3|X1=820|Y1=270|X2=820|Y2=260|X3=820|Y3=250
|RECORD=27|IndexInSheet=163|OwnerPartId=-1|LineWidth=1|Color=8388608|LocationCount=3|X1=820|Y1=260|X2=840|Y2=260|X3=840|Y3=270
|RECORD=27|IndexInSheet=164|OwnerPartId=-1|LineWidth=1|Color=8388608|LocationCount=3|X1=840|Y1=260|X2=860|Y2=260|X3=860|Y3=270
|RECORD=27|IndexInSheet=165|OwnerPartId=-1|LineWidth=1|Color=8388608|LocationCount=4|X1=850|Y1=530|X2=880|Y2=530|X3=880|Y3=470|X4=910|Y4=470
|RECORD=27|IndexInSheet=166|OwnerPartId=-1|LineWidth=1|Color=8388608|LocationCount=2|X1=850|Y1=470|X2=850|Y2=480
|RECORD=27|IndexInSheet=167|OwnerPartId=-1|LineWidth=1|Color=8388608|LocationCount=2|X1=750|Y1=440|X2=780|Y2=440
|RECORD=27|IndexInSheet=168|OwnerPartId=-1|LineWidth=1|Color=8388608|LocationCount=2|X1=820|Y1=440|X2=910|Y2=440
|RECORD=27|IndexInSheet=169|OwnerPartId=-1|LineWidth=1|Color=8388608|LocationCount=3|X1=640|Y1=350|X2=670|Y2=350|X3=910|Y3=350
|RECORD=27|IndexInSheet=170|OwnerPartId=-1|LineWidth=1|Color=8388608|LocationCount=3|X1=640|Y1=340|X2=690|Y2=340|X3=910|Y3=340
|RECORD=27|IndexInSheet=171|OwnerPartId=-1|LineWidth=1|Color=8388608|LocationCount=4|X1=1030|Y1=470|X2=1060|Y2=470|X3=1060|Y3=460|X4=1060|Y4=310
|RECORD=27|IndexInSheet=172|OwnerPartId=-1|LineWidth=1|Color=8388608|LocationCount=2|X1=1030|Y1=460|X2=1060|Y2=460
|RECORD=27|IndexInSheet=173|OwnerPartId=-1|LineWidth=1|Color=8388608|LocationCount=3|X1=1030|Y1=340|X2=1260|Y2=340|X3=1320|Y3=340
|RECORD=27|IndexInSheet=174|OwnerPartId=-1|LineWidth=1|Color=8388608|LocationCount=3|X1=1030|Y1=350|X2=1240|Y2=350|X3=1320|Y3=350
|RECORD=27|IndexInSheet=175|OwnerPartId=-1|LineWidth=1|Color=8388608|LocationCount=3|X1=670|Y1=410|X2=670|Y2=430|X3=670|Y3=470
|RECORD=27|IndexInSheet=176|OwnerPartId=-1|LineWidth=1|Color=8388608|LocationCount=3|X1=690|Y1=410|X2=690|Y2=430|X3=670|Y3=430
|RECORD=27|IndexInSheet=177|OwnerPartId=-1|LineWidth=1|Color=8388608|LocationCount=2|X1=670|Y1=370|X2=670|Y2=350
|RECORD=27|IndexInSheet=178|OwnerPartId=-1|LineWidth=1|Color=8388608|LocationCount=2|X1=690|Y1=370|X2=690|Y2=340
|RECORD=27|IndexInSheet=179|OwnerPartId=-1|LineWidth=1|Color=8388608|LocationCount=3|X1=1090|Y1=520|X2=1090|Y2=540|X3=1090|Y3=560
|RECORD=27|IndexInSheet=180|OwnerPartId=-1|LineWidth=1|Color=8388608|LocationCount=3|X1=1110|Y1=520|X2=1110|Y2=540|X3=1090|Y3=540
|RECORD=27|IndexInSheet=181|OwnerPartId=-1|LineWidth=1|Color=8388608|LocationCount=3|X1=1110|Y1=540|X2=1140|Y2=540|X3=1140|Y3=520
|RECORD=27|IndexInSheet=182|OwnerPartId=-1|LineWidth=1|Color=8388608|LocationCount=7|X1=1140|Y1=540|X2=1160|Y2=540|X3=1190|Y3=540|X4=1210|Y4=540|X5=1240|Y5=540|X6=1260|Y6=540|X7=1260|Y7=520
|RECORD=27|IndexInSheet=183|OwnerPartId=-1|LineWidth=1|Color=8388608|LocationCount=2|X1=1240|Y1=520|X2=1240|Y2=540
|RECORD=27|IndexInSheet=184|OwnerPartId=-1|LineWidth=1|Color=8388608|LocationCount=2|X1=1210|Y1=520|X2=1210|Y2=540
|RECORD=27|IndexInSheet=185|OwnerPartId=-1|LineWidth=1|Color=8388608|LocationCount=2|X1=1190|Y1=520|X2=1190|Y2=540
|RECORD=27|IndexInSheet=186|OwnerPartId=-1|LineWidth=1|Color=8388608|LocationCount=2|X1=1160|Y1=520|X2=1160|Y2=540
|RECORD=27|IndexInSheet=187|OwnerPartId=-1|LineWidth=1|Color=8388608|LocationCount=3|X1=1030|Y1=370|X2=1210|Y2=370|X3=1320|Y3=370
|RECORD=27|IndexInSheet=188|OwnerPartId=-1|LineWidth=1|Color=8388608|LocationCount=3|X1=1320|Y1=380|X2=1190|Y2=380|X3=1030|Y3=380
|RECORD=27|IndexInSheet=189|OwnerPartId=-1|LineWidth=1|Color=8388608|LocationCount=3|X1=1030|Y1=400|X2=1160|Y2=400|X3=1320|Y3=400
|RECORD=27|IndexInSheet=190|OwnerPartId=-1|LineWidth=1|Color=8388608|LocationCount=3|X1=1320|Y1=410|X2=1140|Y2=410|X3=1030|Y3=410
|RECORD=27|IndexInSheet=191|OwnerPartId=-1|LineWidth=1|Color=8388608|LocationCount=3|X1=1030|Y1=430|X2=1110|Y2=430|X3=1320|Y3=430
|RECORD=27|IndexInSheet=192|OwnerPartId=-1|LineWidth=1|Color=8388608|LocationCount=3|X1=1320|Y1=440|X2=1090|Y2=440|X3=1030|Y3=440
|RECORD=27|IndexInSheet=193|OwnerPartId=-1|LineWidth=1|Color=8388608|LocationCount=2|X1=1090|Y1=480|X2=1090|Y2=440
|RECORD=27|IndexInSheet=194|OwnerPartId=-1|LineWidth=1|Color=8388608|LocationCount=2|X1=1110|Y1=480|X2=1110|Y2=430
|RECORD=27|IndexInSheet=195|OwnerPartId=-1|LineWidth=1|Color=8388608|LocationCount=2|X1=1140|Y1=480|X2=1140|Y2=410
|RECORD=27|IndexInSheet=196|OwnerPartId=-1|LineWidth=1|Color=8388608|LocationCount=2|X1=1160|Y1=480|X2=1160|Y2=400
|RECORD=27|IndexInSheet=197|OwnerPartId=-1|LineWidth=1|Color=8388608|LocationCount=2|X1=1190|Y1=480|X2=1190|Y2=380
|RECORD=27|IndexInSheet=198|OwnerPartId=-1|LineWidth=1|Color=8388608|LocationCount=2|X1=1210|Y1=480|X2=1210|Y2=370
|RECORD=27|IndexInSheet=199|OwnerPartId=-1|LineWidth=1|Color=8388608|LocationCount=2|X1=1240|Y1=480|X2=1240|Y2=350
|RECORD=27|IndexInSheet=200|OwnerPartId=-1|LineWidth=1|Color=8388608|LocationCount=2|X1=1260|Y1=480|X2=1260|Y2=340
|RECORD=27|IndexInSheet=201|OwnerPartId=-1|LineWidth=1|Color=8388608|LocationCount=3|X1=850|Y1=500|X2=850|Y2=530|X3=850|Y3=550
|RECORD=27|IndexInSheet=202|OwnerPartId=-1|LineWidth=1|Color=8388608|LocationCount=2|X1=220|Y1=610|X2=180|Y2=610
|RECORD=27|IndexInSheet=203|OwnerPartId=-1|LineWidth=1|Color=8388608|LocationCount=3|X1=280|Y1=650|X2=340|Y2=650|X3=420|Y3=650
|RECORD=27|IndexInSheet=204|OwnerPartId=-1|LineWidth=1|Color=8388608|LocationCount=3|X1=280|Y1=690|X2=320|Y2=690|X3=420|Y3=690
|RECORD=27|IndexInSheet=205|OwnerPartId=-1|LineWidth=1|Color=8388608|LocationCount=3|X1=280|Y1=730|X2=300|Y2=730|X3=420|Y3=730
|RECORD=27|IndexInSheet=206|OwnerPartId=-1|LineWidth=1|Color=8388608|LocationCount=2|X1=340|Y1=780|X2=360|Y2=780
|RECORD=27|IndexInSheet=207|OwnerPartId=-1|LineWidth=1|Color=8388608|LocationCount=3|X1=280|Y1=570|X2=360|Y2=570|X3=420|Y3=570
|RECORD=27|IndexInSheet=208|OwnerPartId=-1|LineWidth=1|Color=8388608|LocationCount=3|X1=280|Y1=560|X2=380|Y2=560|X3=420|Y3=560
|RECORD=27|IndexInSheet=209|OwnerPartId=-1|LineWidth=1|Color=8388608|LocationCount=8|X1=180|Y1=530|X2=180|Y2=560|X3=180|Y3=570|X4=180|Y4=610|X5=180|Y5=650|X6=180|Y6=690|X7=180|Y7=730|X8=220|Y8=730
|RECORD=27|IndexInSheet=210|OwnerPartId=-1|LineWidth=1|Color=8388608|LocationCount=2|X1=220|Y1=570|X2=180|Y2=570
|RECORD=27|IndexInSheet=211|OwnerPartId=-1|LineWidth=1|Color=8388608|LocationCount=2|X1=180|Y1=560|X2=220|Y2=560
|RECORD=27|IndexInSheet=212|OwnerPartId=-1|LineWidth=1|Color=8388608|LocationCount=2|X1=360|Y1=740|X2=360|Y2=570
|RECORD=27|IndexInSheet=213|OwnerPartId=-1|LineWidth=1|Color=8388608|LocationCount=2|X1=360|Y1=780|X2=380|Y2=780
|RECORD=27|IndexInSheet=214|OwnerPartId=-1|LineWidth=1|Color=8388608|LocationCount=2|X1=380|Y1=740|X2=380|Y2=560
|RECORD=17|IndexInSheet=215|OwnerPartId=-1|Style=1|ShowNetName=T|Location.X=450|Location.Y=200|Orientation=2|Color=255|FontID=1|Text=DIP_SW_GPS2_SEL|IsCrossSheetConnector=T
|RECORD=4|IndexInSheet=216|OwnerPartId=-1|Location.X=420|Location.Y=250|Color=8388608|FontID=1|Text=GPS2_SEL = 0 for RCB, 1 for M2
|RECORD=1|LibReference=8706943c75ba83719d021d2fdc84c58|ComponentDescription=LED GREEN CLEAR SMD|PartCount=2|DisplayModeCount=1|IndexInSheet=217|OwnerPartId=-1|Location.X=570|Location.Y=200|Orientation=2|CurrentPartId=1|LibraryPath=*|SourceLibraryName=Altium Content Vault|TargetFileName=*|AreaColor=11599871|Color=128|PartIDLocked=T|DesignItemId=CMP-2000-05198-2|AllPinCount=2
|RECORD=2|OwnerIndex=1638|OwnerPartId=1|Electrical=4|PinConglomerate=48|PinLength=20|Location.X=550|Location.Y=200|Name=A|Designator=2|PinPropagationDelay=0.000000E+000
|RECORD=2|OwnerIndex=1638|OwnerPartId=1|Electrical=4|PinConglomerate=50|PinLength=20|Location.X=530|Location.Y=200|Name=C|Designator=1|PinPropagationDelay=0.000000E+000
|RECORD=13|OwnerIndex=1638|IsNotAccesible=T|IndexInSheet=2|OwnerPartId=1|Location.X=550|Location.Y=190|Corner.X=550|Corner.Y=210|LineWidth=1|Color=16711680
|RECORD=13|OwnerIndex=1638|IsNotAccesible=T|IndexInSheet=3|OwnerPartId=1|Location.X=530|Location.Y=190|Corner.X=530|Corner.Y=210|LineWidth=1|Color=16711680
|RECORD=13|OwnerIndex=1638|IsNotAccesible=T|IndexInSheet=4|OwnerPartId=1|Location.X=550|Location.Y=190|Corner.X=530|Corner.Y=200|LineWidth=1|Color=16711680
|RECORD=13|OwnerIndex=1638|IsNotAccesible=T|IndexInSheet=5|OwnerPartId=1|Location.X=550|Location.Y=210|Corner.X=530|Corner.Y=200|LineWidth=1|Color=16711680
|RECORD=13|OwnerIndex=1638|IsNotAccesible=T|IndexInSheet=6|OwnerPartId=1|Location.X=545|Location.Y=188|Corner.X=535|Corner.Y=178|LineWidth=1|Color=16711680
|RECORD=13|OwnerIndex=1638|IsNotAccesible=T|IndexInSheet=7|OwnerPartId=1|Location.X=535|Location.Y=178|Corner.X=540|Corner.Y=178|LineWidth=1|Color=16711680
|RECORD=13|OwnerIndex=1638|IsNotAccesible=T|IndexInSheet=8|OwnerPartId=1|Location.X=535|Location.Y=178|Corner.X=535|Corner.Y=183|LineWidth=1|Color=16711680
|RECORD=13|OwnerIndex=1638|IsNotAccesible=T|IndexInSheet=9|OwnerPartId=1|Location.X=538|Location.Y=192|Corner.X=528|Corner.Y=182|LineWidth=1|Color=16711680
|RECORD=13|OwnerIndex=1638|IsNotAccesible=T|IndexInSheet=10|OwnerPartId=1|Location.X=528|Location.Y=182|Corner.X=533|Corner.Y=182|LineWidth=1|Color=16711680
|RECORD=13|OwnerIndex=1638|IsNotAccesible=T|IndexInSheet=11|OwnerPartId=1|Location.X=528|Location.Y=182|Corner.X=528|Corner.Y=187|LineWidth=1|Color=16711680
|RECORD=13|OwnerIndex=1638|IsNotAccesible=T|IndexInSheet=12|OwnerPartId=1|Location.X=550|Location.Y=200|Corner.X=553|Corner.Y=200|LineWidth=1|Color=16711680
|RECORD=13|OwnerIndex=1638|IsNotAccesible=T|IndexInSheet=13|OwnerPartId=1|Location.X=530|Location.Y=200|Corner.X=527|Corner.Y=200|LineWidth=1|Color=16711680
|RECORD=41|OwnerIndex=1638|IndexInSheet=14|OwnerPartId=-1|Location.X=508|Location.Y=211|Color=8388608|FontID=1|IsHidden=T|Text=0.8mm|Name=Width
|RECORD=41|OwnerIndex=1638|IndexInSheet=15|OwnerPartId=-1|Location.X=508|Location.Y=211|Color=8388608|FontID=1|IsHidden=T|Text=0603|Name=Case Code (Imperial)
|RECORD=41|OwnerIndex=1638|IndexInSheet=16|OwnerPartId=-1|Location.X=508|Location.Y=211|Color=8388608|FontID=1|IsHidden=T|Text=2|Name=Number of Pins
|RECORD=41|OwnerIndex=1638|IndexInSheet=17|OwnerPartId=-1|Location.X=508|Location.Y=211|Color=8388608|FontID=1|IsHidden=T|Text=75mW|Name=Max Power Dissipation
|RECORD=41|OwnerIndex=1638|IndexInSheet=18|OwnerPartId=-1|Location.X=508|Location.Y=211|Color=8388608|FontID=1|IsHidden=T|Text=30mA|Name=Forward Current
|RECORD=41|OwnerIndex=1638|IndexInSheet=19|OwnerPartId=-1|Location.X=508|Location.Y=211|Color=8388608|FontID=1|IsHidden=T|Text=Lead Free|Name=Lead Free
|RECORD=41|OwnerIndex=1638|IndexInSheet=20|OwnerPartId=-1|Location.X=508|Location.Y=211|Color=8388608|FontID=1|IsHidden=T|Text=5V|Name=Reverse Voltage
|RECORD=41|OwnerIndex=1638|IndexInSheet=21|OwnerPartId=-1|Location.X=508|Location.Y=211|Color=8388608|FontID=1|IsHidden=T|Text=Colorless|Name=Lens Color
|RECORD=41|OwnerIndex=1638|IndexInSheet=22|OwnerPartId=-1|Location.X=508|Location.Y=211|Color=8388608|FontID=1|IsHidden=T|Text=2V|Name=Forward Voltage
|RECORD=41|OwnerIndex=1638|IndexInSheet=23|OwnerPartId=-1|Location.X=508|Location.Y=211|Color=8388608|FontID=1|IsHidden=T|Text=Tape and Reel|Name=Packaging
|RECORD=41|OwnerIndex=1638|IndexInSheet=24|OwnerPartId=-1|Location.X=508|Location.Y=211|Color=8388608|FontID=1|IsHidden=T|Text=1|Name=Package Quantity
|RECORD=41|OwnerIndex=1638|IndexInSheet=25|OwnerPartId=-1|Location.X=508|Location.Y=211|Color=8388608|FontID=1|IsHidden=T|Text=-55°C|Name=Min Operating Temperature
|RECORD=41|OwnerIndex=1638|IndexInSheet=26|OwnerPartId=-1|Location.X=508|Location.Y=211|Color=8388608|FontID=1|IsHidden=T|Text=0603|Name=Case/Package
|RECORD=41|OwnerIndex=1638|IndexInSheet=27|OwnerPartId=-1|Location.X=508|Location.Y=211|Color=8388608|FontID=1|IsHidden=T|Text=1.6mm|Name=Length
|RECORD=41|OwnerIndex=1638|IndexInSheet=28|OwnerPartId=-1|Location.X=508|Location.Y=211|Color=8388608|FontID=1|IsHidden=T|Text=75mW|Name=Power Dissipation
|RECORD=41|OwnerIndex=1638|IndexInSheet=29|OwnerPartId=-1|Location.X=508|Location.Y=211|Color=8388608|FontID=1|IsHidden=T|Text=571nm|Name=Dominant Wavelength
|RECORD=41|OwnerIndex=1638|IndexInSheet=30|OwnerPartId=-1|Location.X=508|Location.Y=211|Color=8388608|FontID=1|IsHidden=T|Text=0.8mm|Name=Depth
|RECORD=41|OwnerIndex=1638|IndexInSheet=31|OwnerPartId=-1|Location.X=508|Location.Y=211|Color=8388608|FontID=1|IsHidden=T|Text=No|Name=Radiation Hardening
|RECORD=41|OwnerIndex=1638|IndexInSheet=32|OwnerPartId=-1|Location.X=508|Location.Y=211|Color=8388608|FontID=1|IsHidden=T|Text=Surface Mount|Name=Mount
|RECORD=41|OwnerIndex=1638|IndexInSheet=33|OwnerPartId=-1|Location.X=508|Location.Y=211|Color=8388608|FontID=1|IsHidden=T|Text=85°C|Name=Max Operating Temperature
|RECORD=41|OwnerIndex=1638|IndexInSheet=34|OwnerPartId=-1|Location.X=508|Location.Y=211|Color=8388608|FontID=1|IsHidden=T|Text=Green|Name=Color
|RECORD=41|OwnerIndex=1638|IndexInSheet=35|OwnerPartId=-1|Location.X=508|Location.Y=211|Color=8388608|FontID=1|IsHidden=T|Text=75mW|Name=Power Rating
|RECORD=41|OwnerIndex=1638|IndexInSheet=36|OwnerPartId=-1|Location.X=508|Location.Y=211|Color=8388608|FontID=1|IsHidden=T|Text=0.55mm|Name=Height
|RECORD=41|OwnerIndex=1638|IndexInSheet=37|OwnerPartId=-1|Location.X=508|Location.Y=211|Color=8388608|FontID=1|IsHidden=T|Text=1|Name=Number of LEDs
|RECORD=41|OwnerIndex=1638|IndexInSheet=38|OwnerPartId=-1|Location.X=508|Location.Y=211|Color=8388608|FontID=1|IsHidden=T|Text=130°|Name=Viewing Angle
|RECORD=41|OwnerIndex=1638|IndexInSheet=39|OwnerPartId=-1|Location.X=508|Location.Y=211|Color=8388608|FontID=1|IsHidden=T|Text=Rectangular|Name=Lens Style
|RECORD=41|OwnerIndex=1638|IndexInSheet=40|OwnerPartId=-1|Location.X=508|Location.Y=211|Color=8388608|FontID=1|IsHidden=T|Text=Green|Name=Illumination Color
|RECORD=41|OwnerIndex=1638|IndexInSheet=41|OwnerPartId=-1|Location.X=508|Location.Y=211|Color=8388608|FontID=1|IsHidden=T|Text=20mA|Name=Test Current
|RECORD=41|OwnerIndex=1638|IndexInSheet=42|OwnerPartId=-1|Location.X=508|Location.Y=211|Color=8388608|FontID=1|IsHidden=T|Text=1608|Name=Case Code (Metric)
|RECORD=41|OwnerIndex=1638|IndexInSheet=43|OwnerPartId=-1|Location.X=508|Location.Y=211|Color=8388608|FontID=1|IsHidden=T|Text=Clear|Name=Lens Transparency
|RECORD=41|OwnerIndex=1638|IndexInSheet=44|OwnerPartId=-1|Location.X=508|Location.Y=211|Color=8388608|FontID=1|IsHidden=T|Text=35mcd|Name=Luminous Intensity
|RECORD=41|OwnerIndex=1638|IndexInSheet=45|OwnerPartId=-1|Location.X=508|Location.Y=211|Color=8388608|FontID=1|IsHidden=T|Text=1|Name=Number of Elements
|RECORD=41|OwnerIndex=1638|IndexInSheet=46|OwnerPartId=-1|Location.X=508|Location.Y=211|Color=8388608|FontID=1|IsHidden=T|Text=574nm|Name=Wavelength
|RECORD=34|OwnerIndex=1638|IndexInSheet=-1|OwnerPartId=-1|Location.X=526|Location.Y=211|Color=8388608|FontID=1|Text=D12|Name=Designator|ReadOnlyState=1
|RECORD=41|OwnerIndex=1638|IndexInSheet=-1|OwnerPartId=1|Location.X=526|Location.Y=167|Color=8388608|FontID=1|Text=LTST-C191KGKT|Name=Comment
|RECORD=44|OwnerIndex=1638
|RECORD=45|OwnerIndex=1690|IndexInSheet=-1|UseComponentLibrary=T|ModelName=FP-LTST-C191KGKT-MFG|ModelType=PCBLIB|DatafileCount=1|ModelDatafileEntity0=FP-LTST-C191KGKT-MFG|ModelDatafileKind0=PCBLib|IsCurrent=T|DatalinksLocked=T|DatabaseDatalinksLocked=T
|RECORD=46|OwnerIndex=1691
|RECORD=48|OwnerIndex=1691
|RECORD=1|LibReference=RES|PartCount=2|DisplayModeCount=2|IndexInSheet=218|OwnerPartId=-1|Location.X=490|Location.Y=190|Orientation=2|CurrentPartId=1|SourceLibraryName=Altium Content Vault|TargetFileName=*|AreaColor=11599871|Color=128|PartIDLocked=F|DesignItemId=CMP-2002-08352-1|AllPinCount=2
|RECORD=2|OwnerIndex=1694|OwnerPartId=1|OwnerPartDisplayMode=1|FormalType=1|Electrical=4|PinConglomerate=34|PinLength=10|Location.X=470|Location.Y=200|Name=2|Designator=2|PinPropagationDelay=0.000000E+000
|RECORD=2|OwnerIndex=1694|OwnerPartId=1|OwnerPartDisplayMode=1|FormalType=1|Electrical=4|PinConglomerate=32|PinLength=10|Location.X=490|Location.Y=200|Name=1|Designator=1|PinPropagationDelay=0.000000E+000
|RECORD=14|OwnerIndex=1694|IsNotAccesible=T|IndexInSheet=2|OwnerPartId=1|OwnerPartDisplayMode=1|Location.X=470|Location.Y=196|Corner.X=490|Corner.Y=204|LineWidth=1|Color=16711680|AreaColor=11599871
|RECORD=2|OwnerIndex=1694|OwnerPartId=1|FormalType=1|Electrical=4|PinConglomerate=34|PinLength=10|Location.X=470|Location.Y=200|Name=2|Designator=2|PinPropagationDelay=0.000000E+000
|RECORD=2|OwnerIndex=1694|OwnerPartId=1|FormalType=1|Electrical=4|PinConglomerate=32|PinLength=10|Location.X=490|Location.Y=200|Name=1|Designator=1|PinPropagationDelay=0.000000E+000
|RECORD=6|OwnerIndex=1694|IsNotAccesible=T|IndexInSheet=5|OwnerPartId=1|LineWidth=1|Color=16711680|LocationCount=10|X1=470|Y1=200|X2=474|Y2=200|X3=475|Y3=202|X4=477|Y4=198|X5=479|Y5=202|X6=481|Y6=198|X7=483|Y7=202|X8=485|Y8=198|X9=486|Y9=200|X10=490|Y10=200
|RECORD=41|OwnerIndex=1694|IndexInSheet=6|OwnerPartId=-1|Location.X=458|Location.Y=203|Color=8388608|FontID=1|IsHidden=T|Text=Vishay Dale|Name=Manufacturer
|RECORD=41|OwnerIndex=1694|IndexInSheet=7|OwnerPartId=-1|Location.X=458|Location.Y=203|Color=8388608|FontID=1|IsHidden=T|Text=CRCW0402200RFKTD|Name=Part Number
|RECORD=34|OwnerIndex=1694|IndexInSheet=-1|OwnerPartId=-1|Location.X=469|Location.Y=203|Color=8388608|FontID=1|Text=R178|Name=Designator|ReadOnlyState=1
|RECORD=41|OwnerIndex=1694|IndexInSheet=-1|OwnerPartId=-1|Location.X=469|Location.Y=187|Color=8388608|FontID=1|Text=200_1%_0402|Name=Comment
|RECORD=44|OwnerIndex=1694
|RECORD=45|OwnerIndex=1709|IndexInSheet=-1|Description=Chip Resistor, 2-Leads, Body 1.00x0.50mm, IPC Medium Density|UseComponentLibrary=T|ModelName=RESC1005X40X25NL05T05|ModelType=PCBLIB|DatafileCount=1|ModelDatafileEntity0=RESC1005X40X25NL05T05|ModelDatafileKind0=PCBLib|IsCurrent=T|DatalinksLocked=T|DatabaseDatalinksLocked=T
|RECORD=46|OwnerIndex=1710
|RECORD=48|OwnerIndex=1710
|RECORD=41|OwnerIndex=1712|IndexInSheet=-1|OwnerPartId=-1|Color=8388608|FontID=1|IsHidden=T|Text=2D|Name=Available Preview Images
|RECORD=45|OwnerIndex=1709|IndexInSheet=-1|Description=Chip Resistor, 2-Leads, Body 1.00x0.50mm, IPC Low Density|UseComponentLibrary=T|ModelName=RESC1005X40X25ML05T05|ModelType=PCBLIB|DatafileCount=1|ModelDatafileEntity0=RESC1005X40X25ML05T05|ModelDatafileKind0=PCBLib|DatalinksLocked=T|DatabaseDatalinksLocked=T
|RECORD=46|OwnerIndex=1714
|RECORD=48|OwnerIndex=1714
|RECORD=41|OwnerIndex=1716|IndexInSheet=-1|OwnerPartId=-1|Color=8388608|FontID=1|IsHidden=T|Text=2D|Name=Available Preview Images
|RECORD=45|OwnerIndex=1709|IndexInSheet=-1|Description=Chip Resistor, 2-Leads, Body 1.00x0.50mm, IPC High Density|UseComponentLibrary=T|ModelName=RESC1005X40X25LL05T05|ModelType=PCBLIB|DatafileCount=1|ModelDatafileEntity0=RESC1005X40X25LL05T05|ModelDatafileKind0=PCBLib|DatalinksLocked=T|DatabaseDatalinksLocked=T
|RECORD=46|OwnerIndex=1718
|RECORD=48|OwnerIndex=1718
|RECORD=41|OwnerIndex=1720|IndexInSheet=-1|OwnerPartId=-1|Color=8388608|FontID=1|IsHidden=T|Text=2D|Name=Available Preview Images
|RECORD=17|IndexInSheet=219|OwnerPartId=-1|ShowNetName=T|Location.X=590|Location.Y=220|Orientation=1|Color=128|FontID=1|Text=+3.3V
|RECORD=17|IndexInSheet=220|OwnerPartId=-1|Style=1|ShowNetName=T|Location.X=450|Location.Y=90|Orientation=2|Color=255|FontID=1|Text=DIP_SW_GPS1_SEL|IsCrossSheetConnector=T
|RECORD=1|LibReference=8706943c75ba83719d021d2fdc84c58|ComponentDescription=LED GREEN CLEAR SMD|PartCount=2|DisplayModeCount=1|IndexInSheet=221|OwnerPartId=-1|Location.X=570|Location.Y=90|Orientation=2|CurrentPartId=1|LibraryPath=*|SourceLibraryName=Altium Content Vault|TargetFileName=*|AreaColor=11599871|Color=128|PartIDLocked=T|DesignItemId=CMP-2000-05198-2|AllPinCount=2
|RECORD=2|OwnerIndex=1724|OwnerPartId=1|Electrical=4|PinConglomerate=48|PinLength=20|Location.X=550|Location.Y=90|Name=A|Designator=2|PinPropagationDelay=0.000000E+000
|RECORD=2|OwnerIndex=1724|OwnerPartId=1|Electrical=4|PinConglomerate=50|PinLength=20|Location.X=530|Location.Y=90|Name=C|Designator=1|PinPropagationDelay=0.000000E+000
|RECORD=13|OwnerIndex=1724|IsNotAccesible=T|IndexInSheet=2|OwnerPartId=1|Location.X=550|Location.Y=80|Corner.X=550|Corner.Y=100|LineWidth=1|Color=16711680
|RECORD=13|OwnerIndex=1724|IsNotAccesible=T|IndexInSheet=3|OwnerPartId=1|Location.X=530|Location.Y=80|Corner.X=530|Corner.Y=100|LineWidth=1|Color=16711680
|RECORD=13|OwnerIndex=1724|IsNotAccesible=T|IndexInSheet=4|OwnerPartId=1|Location.X=550|Location.Y=80|Corner.X=530|Corner.Y=90|LineWidth=1|Color=16711680
|RECORD=13|OwnerIndex=1724|IsNotAccesible=T|IndexInSheet=5|OwnerPartId=1|Location.X=550|Location.Y=100|Corner.X=530|Corner.Y=90|LineWidth=1|Color=16711680
|RECORD=13|OwnerIndex=1724|IsNotAccesible=T|IndexInSheet=6|OwnerPartId=1|Location.X=545|Location.Y=78|Corner.X=535|Corner.Y=68|LineWidth=1|Color=16711680
|RECORD=13|OwnerIndex=1724|IsNotAccesible=T|IndexInSheet=7|OwnerPartId=1|Location.X=535|Location.Y=68|Corner.X=540|Corner.Y=68|LineWidth=1|Color=16711680
|RECORD=13|OwnerIndex=1724|IsNotAccesible=T|IndexInSheet=8|OwnerPartId=1|Location.X=535|Location.Y=68|Corner.X=535|Corner.Y=73|LineWidth=1|Color=16711680
|RECORD=13|OwnerIndex=1724|IsNotAccesible=T|IndexInSheet=9|OwnerPartId=1|Location.X=538|Location.Y=82|Corner.X=528|Corner.Y=72|LineWidth=1|Color=16711680
|RECORD=13|OwnerIndex=1724|IsNotAccesible=T|IndexInSheet=10|OwnerPartId=1|Location.X=528|Location.Y=72|Corner.X=533|Corner.Y=72|LineWidth=1|Color=16711680
|RECORD=13|OwnerIndex=1724|IsNotAccesible=T|IndexInSheet=11|OwnerPartId=1|Location.X=528|Location.Y=72|Corner.X=528|Corner.Y=77|LineWidth=1|Color=16711680
|RECORD=13|OwnerIndex=1724|IsNotAccesible=T|IndexInSheet=12|OwnerPartId=1|Location.X=550|Location.Y=90|Corner.X=553|Corner.Y=90|LineWidth=1|Color=16711680
|RECORD=13|OwnerIndex=1724|IsNotAccesible=T|IndexInSheet=13|OwnerPartId=1|Location.X=530|Location.Y=90|Corner.X=527|Corner.Y=90|LineWidth=1|Color=16711680
|RECORD=41|OwnerIndex=1724|IndexInSheet=14|OwnerPartId=-1|Location.X=508|Location.Y=101|Color=8388608|FontID=1|IsHidden=T|Text=0.8mm|Name=Width
|RECORD=41|OwnerIndex=1724|IndexInSheet=15|OwnerPartId=-1|Location.X=508|Location.Y=101|Color=8388608|FontID=1|IsHidden=T|Text=0603|Name=Case Code (Imperial)
|RECORD=41|OwnerIndex=1724|IndexInSheet=16|OwnerPartId=-1|Location.X=508|Location.Y=101|Color=8388608|FontID=1|IsHidden=T|Text=2|Name=Number of Pins
|RECORD=41|OwnerIndex=1724|IndexInSheet=17|OwnerPartId=-1|Location.X=508|Location.Y=101|Color=8388608|FontID=1|IsHidden=T|Text=75mW|Name=Max Power Dissipation
|RECORD=41|OwnerIndex=1724|IndexInSheet=18|OwnerPartId=-1|Location.X=508|Location.Y=101|Color=8388608|FontID=1|IsHidden=T|Text=30mA|Name=Forward Current
|RECORD=41|OwnerIndex=1724|IndexInSheet=19|OwnerPartId=-1|Location.X=508|Location.Y=101|Color=8388608|FontID=1|IsHidden=T|Text=Lead Free|Name=Lead Free
|RECORD=41|OwnerIndex=1724|IndexInSheet=20|OwnerPartId=-1|Location.X=508|Location.Y=101|Color=8388608|FontID=1|IsHidden=T|Text=5V|Name=Reverse Voltage
|RECORD=41|OwnerIndex=1724|IndexInSheet=21|OwnerPartId=-1|Location.X=508|Location.Y=101|Color=8388608|FontID=1|IsHidden=T|Text=Colorless|Name=Lens Color
|RECORD=41|OwnerIndex=1724|IndexInSheet=22|OwnerPartId=-1|Location.X=508|Location.Y=101|Color=8388608|FontID=1|IsHidden=T|Text=2V|Name=Forward Voltage
|RECORD=41|OwnerIndex=1724|IndexInSheet=23|OwnerPartId=-1|Location.X=508|Location.Y=101|Color=8388608|FontID=1|IsHidden=T|Text=Tape and Reel|Name=Packaging
|RECORD=41|OwnerIndex=1724|IndexInSheet=24|OwnerPartId=-1|Location.X=508|Location.Y=101|Color=8388608|FontID=1|IsHidden=T|Text=1|Name=Package Quantity
|RECORD=41|OwnerIndex=1724|IndexInSheet=25|OwnerPartId=-1|Location.X=508|Location.Y=101|Color=8388608|FontID=1|IsHidden=T|Text=-55°C|Name=Min Operating Temperature
|RECORD=41|OwnerIndex=1724|IndexInSheet=26|OwnerPartId=-1|Location.X=508|Location.Y=101|Color=8388608|FontID=1|IsHidden=T|Text=0603|Name=Case/Package
|RECORD=41|OwnerIndex=1724|IndexInSheet=27|OwnerPartId=-1|Location.X=508|Location.Y=101|Color=8388608|FontID=1|IsHidden=T|Text=1.6mm|Name=Length
|RECORD=41|OwnerIndex=1724|IndexInSheet=28|OwnerPartId=-1|Location.X=508|Location.Y=101|Color=8388608|FontID=1|IsHidden=T|Text=75mW|Name=Power Dissipation
|RECORD=41|OwnerIndex=1724|IndexInSheet=29|OwnerPartId=-1|Location.X=508|Location.Y=101|Color=8388608|FontID=1|IsHidden=T|Text=571nm|Name=Dominant Wavelength
|RECORD=41|OwnerIndex=1724|IndexInSheet=30|OwnerPartId=-1|Location.X=508|Location.Y=101|Color=8388608|FontID=1|IsHidden=T|Text=0.8mm|Name=Depth
|RECORD=41|OwnerIndex=1724|IndexInSheet=31|OwnerPartId=-1|Location.X=508|Location.Y=101|Color=8388608|FontID=1|IsHidden=T|Text=No|Name=Radiation Hardening
|RECORD=41|OwnerIndex=1724|IndexInSheet=32|OwnerPartId=-1|Location.X=508|Location.Y=101|Color=8388608|FontID=1|IsHidden=T|Text=Surface Mount|Name=Mount
|RECORD=41|OwnerIndex=1724|IndexInSheet=33|OwnerPartId=-1|Location.X=508|Location.Y=101|Color=8388608|FontID=1|IsHidden=T|Text=85°C|Name=Max Operating Temperature
|RECORD=41|OwnerIndex=1724|IndexInSheet=34|OwnerPartId=-1|Location.X=508|Location.Y=101|Color=8388608|FontID=1|IsHidden=T|Text=Green|Name=Color
|RECORD=41|OwnerIndex=1724|IndexInSheet=35|OwnerPartId=-1|Location.X=508|Location.Y=101|Color=8388608|FontID=1|IsHidden=T|Text=75mW|Name=Power Rating
|RECORD=41|OwnerIndex=1724|IndexInSheet=36|OwnerPartId=-1|Location.X=508|Location.Y=101|Color=8388608|FontID=1|IsHidden=T|Text=0.55mm|Name=Height
|RECORD=41|OwnerIndex=1724|IndexInSheet=37|OwnerPartId=-1|Location.X=508|Location.Y=101|Color=8388608|FontID=1|IsHidden=T|Text=1|Name=Number of LEDs
|RECORD=41|OwnerIndex=1724|IndexInSheet=38|OwnerPartId=-1|Location.X=508|Location.Y=101|Color=8388608|FontID=1|IsHidden=T|Text=130°|Name=Viewing Angle
|RECORD=41|OwnerIndex=1724|IndexInSheet=39|OwnerPartId=-1|Location.X=508|Location.Y=101|Color=8388608|FontID=1|IsHidden=T|Text=Rectangular|Name=Lens Style
|RECORD=41|OwnerIndex=1724|IndexInSheet=40|OwnerPartId=-1|Location.X=508|Location.Y=101|Color=8388608|FontID=1|IsHidden=T|Text=Green|Name=Illumination Color
|RECORD=41|OwnerIndex=1724|IndexInSheet=41|OwnerPartId=-1|Location.X=508|Location.Y=101|Color=8388608|FontID=1|IsHidden=T|Text=20mA|Name=Test Current
|RECORD=41|OwnerIndex=1724|IndexInSheet=42|OwnerPartId=-1|Location.X=508|Location.Y=101|Color=8388608|FontID=1|IsHidden=T|Text=1608|Name=Case Code (Metric)
|RECORD=41|OwnerIndex=1724|IndexInSheet=43|OwnerPartId=-1|Location.X=508|Location.Y=101|Color=8388608|FontID=1|IsHidden=T|Text=Clear|Name=Lens Transparency
|RECORD=41|OwnerIndex=1724|IndexInSheet=44|OwnerPartId=-1|Location.X=508|Location.Y=101|Color=8388608|FontID=1|IsHidden=T|Text=35mcd|Name=Luminous Intensity
|RECORD=41|OwnerIndex=1724|IndexInSheet=45|OwnerPartId=-1|Location.X=508|Location.Y=101|Color=8388608|FontID=1|IsHidden=T|Text=1|Name=Number of Elements
|RECORD=41|OwnerIndex=1724|IndexInSheet=46|OwnerPartId=-1|Location.X=508|Location.Y=101|Color=8388608|FontID=1|IsHidden=T|Text=574nm|Name=Wavelength
|RECORD=34|OwnerIndex=1724|IndexInSheet=-1|OwnerPartId=-1|Location.X=526|Location.Y=101|Color=8388608|FontID=1|Text=D19|Name=Designator|ReadOnlyState=1
|RECORD=41|OwnerIndex=1724|IndexInSheet=-1|OwnerPartId=1|Location.X=526|Location.Y=57|Color=8388608|FontID=1|Text=LTST-C191KGKT|Name=Comment
|RECORD=44|OwnerIndex=1724
|RECORD=45|OwnerIndex=1776|IndexInSheet=-1|UseComponentLibrary=T|ModelName=FP-LTST-C191KGKT-MFG|ModelType=PCBLIB|DatafileCount=1|ModelDatafileEntity0=FP-LTST-C191KGKT-MFG|ModelDatafileKind0=PCBLib|IsCurrent=T|DatalinksLocked=T|DatabaseDatalinksLocked=T
|RECORD=46|OwnerIndex=1777
|RECORD=48|OwnerIndex=1777
|RECORD=1|LibReference=RES|PartCount=2|DisplayModeCount=2|IndexInSheet=222|OwnerPartId=-1|Location.X=490|Location.Y=80|Orientation=2|CurrentPartId=1|SourceLibraryName=Altium Content Vault|TargetFileName=*|AreaColor=11599871|Color=128|PartIDLocked=F|DesignItemId=CMP-2002-08352-1|AllPinCount=2
|RECORD=2|OwnerIndex=1780|OwnerPartId=1|OwnerPartDisplayMode=1|FormalType=1|Electrical=4|PinConglomerate=34|PinLength=10|Location.X=470|Location.Y=90|Name=2|Designator=2|PinPropagationDelay=0.000000E+000
|RECORD=2|OwnerIndex=1780|OwnerPartId=1|OwnerPartDisplayMode=1|FormalType=1|Electrical=4|PinConglomerate=32|PinLength=10|Location.X=490|Location.Y=90|Name=1|Designator=1|PinPropagationDelay=0.000000E+000
|RECORD=14|OwnerIndex=1780|IsNotAccesible=T|IndexInSheet=2|OwnerPartId=1|OwnerPartDisplayMode=1|Location.X=470|Location.Y=86|Corner.X=490|Corner.Y=94|LineWidth=1|Color=16711680|AreaColor=11599871
|RECORD=2|OwnerIndex=1780|OwnerPartId=1|FormalType=1|Electrical=4|PinConglomerate=34|PinLength=10|Location.X=470|Location.Y=90|Name=2|Designator=2|PinPropagationDelay=0.000000E+000
|RECORD=2|OwnerIndex=1780|OwnerPartId=1|FormalType=1|Electrical=4|PinConglomerate=32|PinLength=10|Location.X=490|Location.Y=90|Name=1|Designator=1|PinPropagationDelay=0.000000E+000
|RECORD=6|OwnerIndex=1780|IsNotAccesible=T|IndexInSheet=5|OwnerPartId=1|LineWidth=1|Color=16711680|LocationCount=10|X1=470|Y1=90|X2=474|Y2=90|X3=475|Y3=92|X4=477|Y4=88|X5=479|Y5=92|X6=481|Y6=88|X7=483|Y7=92|X8=485|Y8=88|X9=486|Y9=90|X10=490|Y10=90
|RECORD=41|OwnerIndex=1780|IndexInSheet=6|OwnerPartId=-1|Location.X=458|Location.Y=93|Color=8388608|FontID=1|IsHidden=T|Text=Vishay Dale|Name=Manufacturer
|RECORD=41|OwnerIndex=1780|IndexInSheet=7|OwnerPartId=-1|Location.X=458|Location.Y=93|Color=8388608|FontID=1|IsHidden=T|Text=CRCW0402200RFKTD|Name=Part Number
|RECORD=34|OwnerIndex=1780|IndexInSheet=-1|OwnerPartId=-1|Location.X=469|Location.Y=93|Color=8388608|FontID=1|Text=R179|Name=Designator|ReadOnlyState=1
|RECORD=41|OwnerIndex=1780|IndexInSheet=-1|OwnerPartId=-1|Location.X=469|Location.Y=77|Color=8388608|FontID=1|Text=200_1%_0402|Name=Comment
|RECORD=44|OwnerIndex=1780
|RECORD=45|OwnerIndex=1795|IndexInSheet=-1|Description=Chip Resistor, 2-Leads, Body 1.00x0.50mm, IPC Medium Density|UseComponentLibrary=T|ModelName=RESC1005X40X25NL05T05|ModelType=PCBLIB|DatafileCount=1|ModelDatafileEntity0=RESC1005X40X25NL05T05|ModelDatafileKind0=PCBLib|IsCurrent=T|DatalinksLocked=T|DatabaseDatalinksLocked=T
|RECORD=46|OwnerIndex=1796
|RECORD=48|OwnerIndex=1796
|RECORD=41|OwnerIndex=1798|IndexInSheet=-1|OwnerPartId=-1|Color=8388608|FontID=1|IsHidden=T|Text=2D|Name=Available Preview Images
|RECORD=45|OwnerIndex=1795|IndexInSheet=-1|Description=Chip Resistor, 2-Leads, Body 1.00x0.50mm, IPC Low Density|UseComponentLibrary=T|ModelName=RESC1005X40X25ML05T05|ModelType=PCBLIB|DatafileCount=1|ModelDatafileEntity0=RESC1005X40X25ML05T05|ModelDatafileKind0=PCBLib|DatalinksLocked=T|DatabaseDatalinksLocked=T
|RECORD=46|OwnerIndex=1800
|RECORD=48|OwnerIndex=1800
|RECORD=41|OwnerIndex=1802|IndexInSheet=-1|OwnerPartId=-1|Color=8388608|FontID=1|IsHidden=T|Text=2D|Name=Available Preview Images
|RECORD=45|OwnerIndex=1795|IndexInSheet=-1|Description=Chip Resistor, 2-Leads, Body 1.00x0.50mm, IPC High Density|UseComponentLibrary=T|ModelName=RESC1005X40X25LL05T05|ModelType=PCBLIB|DatafileCount=1|ModelDatafileEntity0=RESC1005X40X25LL05T05|ModelDatafileKind0=PCBLib|DatalinksLocked=T|DatabaseDatalinksLocked=T
|RECORD=46|OwnerIndex=1804
|RECORD=48|OwnerIndex=1804
|RECORD=41|OwnerIndex=1806|IndexInSheet=-1|OwnerPartId=-1|Color=8388608|FontID=1|IsHidden=T|Text=2D|Name=Available Preview Images
|RECORD=17|IndexInSheet=223|OwnerPartId=-1|ShowNetName=T|Location.X=590|Location.Y=110|Orientation=1|Color=128|FontID=1|Text=+3.3V
|RECORD=27|IndexInSheet=224|OwnerPartId=-1|LineWidth=1|Color=8388608|LocationCount=2|X1=450|Y1=200|X2=460|Y2=200
|RECORD=27|IndexInSheet=225|OwnerPartId=-1|LineWidth=1|Color=8388608|LocationCount=2|X1=500|Y1=200|X2=510|Y2=200
|RECORD=27|IndexInSheet=226|OwnerPartId=-1|LineWidth=1|Color=8388608|LocationCount=3|X1=570|Y1=200|X2=590|Y2=200|X3=590|Y3=220
|RECORD=27|IndexInSheet=227|OwnerPartId=-1|LineWidth=1|Color=8388608|LocationCount=2|X1=450|Y1=90|X2=460|Y2=90
|RECORD=27|IndexInSheet=228|OwnerPartId=-1|LineWidth=1|Color=8388608|LocationCount=2|X1=500|Y1=90|X2=510|Y2=90
|RECORD=27|IndexInSheet=229|OwnerPartId=-1|LineWidth=1|Color=8388608|LocationCount=3|X1=570|Y1=90|X2=590|Y2=90|X3=590|Y3=110
|RECORD=4|IndexInSheet=230|OwnerPartId=-1|Location.X=420|Location.Y=130|Color=8388608|FontID=1|Text=GPS1_SEL = 0 for RCB, 1 for M2
|RECORD=29|IndexInSheet=-1|OwnerPartId=-1|Location.X=180|Location.Y=560|Color=128
|RECORD=29|IndexInSheet=-1|OwnerPartId=-1|Location.X=180|Location.Y=570|Color=128
|RECORD=29|IndexInSheet=-1|OwnerPartId=-1|Location.X=180|Location.Y=610|Color=128
|RECORD=29|IndexInSheet=-1|OwnerPartId=-1|Location.X=180|Location.Y=650|Color=128
|RECORD=29|IndexInSheet=-1|OwnerPartId=-1|Location.X=180|Location.Y=690|Color=128
|RECORD=29|IndexInSheet=-1|OwnerPartId=-1|Location.X=300|Location.Y=730|Color=128
|RECORD=29|IndexInSheet=-1|OwnerPartId=-1|Location.X=300|Location.Y=780|Color=128
|RECORD=29|IndexInSheet=-1|OwnerPartId=-1|Location.X=320|Location.Y=690|Color=128
|RECORD=29|IndexInSheet=-1|OwnerPartId=-1|Location.X=320|Location.Y=780|Color=128
|RECORD=29|IndexInSheet=-1|OwnerPartId=-1|Location.X=340|Location.Y=650|Color=128
|RECORD=29|IndexInSheet=-1|OwnerPartId=-1|Location.X=340|Location.Y=780|Color=128
|RECORD=29|IndexInSheet=-1|OwnerPartId=-1|Location.X=360|Location.Y=570|Color=128
|RECORD=29|IndexInSheet=-1|OwnerPartId=-1|Location.X=360|Location.Y=780|Color=128
|RECORD=29|IndexInSheet=-1|OwnerPartId=-1|Location.X=380|Location.Y=560|Color=128
|RECORD=29|IndexInSheet=-1|OwnerPartId=-1|Location.X=670|Location.Y=350|Color=128
|RECORD=29|IndexInSheet=-1|OwnerPartId=-1|Location.X=670|Location.Y=430|Color=128
|RECORD=29|IndexInSheet=-1|OwnerPartId=-1|Location.X=690|Location.Y=340|Color=128
|RECORD=29|IndexInSheet=-1|OwnerPartId=-1|Location.X=820|Location.Y=260|Color=128
|RECORD=29|IndexInSheet=-1|OwnerPartId=-1|Location.X=840|Location.Y=260|Color=128
|RECORD=29|IndexInSheet=-1|OwnerPartId=-1|Location.X=850|Location.Y=530|Color=128
|RECORD=29|IndexInSheet=-1|OwnerPartId=-1|Location.X=860|Location.Y=830|Color=128
|RECORD=29|IndexInSheet=-1|OwnerPartId=-1|Location.X=900|Location.Y=620|Color=128
|RECORD=29|IndexInSheet=-1|OwnerPartId=-1|Location.X=900|Location.Y=670|Color=128
|RECORD=29|IndexInSheet=-1|OwnerPartId=-1|Location.X=1060|Location.Y=460|Color=128
|RECORD=29|IndexInSheet=-1|OwnerPartId=-1|Location.X=1070|Location.Y=710|Color=128
|RECORD=29|IndexInSheet=-1|OwnerPartId=-1|Location.X=1080|Location.Y=750|Color=128
|RECORD=29|IndexInSheet=-1|OwnerPartId=-1|Location.X=1090|Location.Y=440|Color=128
|RECORD=29|IndexInSheet=-1|OwnerPartId=-1|Location.X=1090|Location.Y=540|Color=128
|RECORD=29|IndexInSheet=-1|OwnerPartId=-1|Location.X=1110|Location.Y=430|Color=128
|RECORD=29|IndexInSheet=-1|OwnerPartId=-1|Location.X=1110|Location.Y=540|Color=128
|RECORD=29|IndexInSheet=-1|OwnerPartId=-1|Location.X=1140|Location.Y=410|Color=128
|RECORD=29|IndexInSheet=-1|OwnerPartId=-1|Location.X=1140|Location.Y=540|Color=128
|RECORD=29|IndexInSheet=-1|OwnerPartId=-1|Location.X=1160|Location.Y=400|Color=128
|RECORD=29|IndexInSheet=-1|OwnerPartId=-1|Location.X=1160|Location.Y=540|Color=128
|RECORD=29|IndexInSheet=-1|OwnerPartId=-1|Location.X=1190|Location.Y=380|Color=128
|RECORD=29|IndexInSheet=-1|OwnerPartId=-1|Location.X=1190|Location.Y=540|Color=128
|RECORD=29|IndexInSheet=-1|OwnerPartId=-1|Location.X=1210|Location.Y=370|Color=128
|RECORD=29|IndexInSheet=-1|OwnerPartId=-1|Location.X=1210|Location.Y=540|Color=128
|RECORD=29|IndexInSheet=-1|OwnerPartId=-1|Location.X=1240|Location.Y=350|Color=128
|RECORD=29|IndexInSheet=-1|OwnerPartId=-1|Location.X=1240|Location.Y=540|Color=128
|RECORD=29|IndexInSheet=-1|OwnerPartId=-1|Location.X=1260|Location.Y=340|Color=128